FILE_TYPE = MACRO_DRAWING;
SET COLOR_WIRE YELLOW;
SET COLOR_PROP ORANGE;
SET COLOR_DOT WHITE;
SET COLOR_ARC YELLOW;
SET COLOR_BODY GREEN;
SET COLOR_NOTE PURPLE;
SET PROP_DISPLAY VALUE;
SET PAGE_NUMBER P27;
FORCEADD OFFPAGE..4
R 2
(-6125 4475);
FORCEPROP 2 LAST $XR1 173 
J 0
(-6496 4475);
DISPLAY 0.638298 (-6496 4475);
PAINT MONO (-6496 4475);
FORCEPROP 2 LAST $XR0 27 
J 0
(-6376 4475);
DISPLAY 0.638298 (-6376 4475);
PAINT MONO (-6376 4475);
FORCEPROP 2 LAST CDS_LIB standard
J 2
(-6125 4475);
DISPLAY INVISIBLE (-6125 4475);
FORCEPROP 1 LAST OFFPAGE TRUE
J 2
(-6450 4350);
DISPLAY 0.872340 (-6450 4350);
PAINT GREEN (-6450 4350);
DISPLAY INVISIBLE (-6450 4350);
FORCEPROP 1 LAST COMMENT_BODY TRUE
J 2
(-6100 4375);
DISPLAY 0.872340 (-6100 4375);
PAINT GREEN (-6100 4375);
DISPLAY INVISIBLE (-6100 4375);
FORCEPROP 2 LAST PATH I10
J 2
(-6300 4550);
DISPLAY 1.021277 (-6300 4550);
DISPLAY INVISIBLE (-6300 4550);
FORCEADD UNIVERSAL_POWER..1
(-8675 4825);
FORCEPROP 3 LASTPIN (-8675 4775) SIG_NAME PVDD18_S5_P0\g
J 0
(-8665 4785);
DISPLAY 0.659574 (-8665 4785);
PAINT MONO (-8665 4785);
DISPLAY INVISIBLE (-8665 4785);
FORCEPROP 1 LAST HDL_POWER PVDD18_S5_P0
J 1
(-8675 4875);
DISPLAY 0.489362 (-8675 4875);
PAINT GREEN (-8675 4875);
FORCEPROP 2 LAST CDS_LIB pure_quanta_power
J 0
(-8675 4825);
DISPLAY INVISIBLE (-8675 4825);
FORCEPROP 1 LAST PATH I100
J 0
(-8625 4850);
DISPLAY 0.872340 (-8625 4850);
PAINT AQUA (-8625 4850);
DISPLAY INVISIBLE (-8625 4850);
FORCEADD OFFPAGE..4
R 2
(-6125 4425);
FORCEPROP 2 LAST $XR1 173 
J 0
(-6496 4425);
DISPLAY 0.638298 (-6496 4425);
PAINT MONO (-6496 4425);
FORCEPROP 2 LAST $XR0 27 
J 0
(-6376 4425);
DISPLAY 0.638298 (-6376 4425);
PAINT MONO (-6376 4425);
FORCEPROP 2 LAST CDS_LIB standard
J 0
(-6125 4425);
DISPLAY INVISIBLE (-6125 4425);
FORCEPROP 1 LAST OFFPAGE TRUE
J 2
(-6450 4300);
DISPLAY 0.872340 (-6450 4300);
PAINT GREEN (-6450 4300);
DISPLAY INVISIBLE (-6450 4300);
FORCEPROP 1 LAST COMMENT_BODY TRUE
J 2
(-6100 4325);
DISPLAY 0.872340 (-6100 4325);
PAINT GREEN (-6100 4325);
DISPLAY INVISIBLE (-6100 4325);
FORCEPROP 2 LAST PATH I11
J 0
(-6075 4500);
DISPLAY 1.021277 (-6075 4500);
DISPLAY INVISIBLE (-6075 4500);
FORCEADD OFFPAGE..4
R 2
(-6125 4375);
FORCEPROP 2 LAST $XR1 173 
J 0
(-6496 4375);
DISPLAY 0.638298 (-6496 4375);
PAINT MONO (-6496 4375);
FORCEPROP 2 LAST $XR0 27 
J 0
(-6376 4375);
DISPLAY 0.638298 (-6376 4375);
PAINT MONO (-6376 4375);
FORCEPROP 2 LAST CDS_LIB standard
J 0
(-6125 4375);
DISPLAY INVISIBLE (-6125 4375);
FORCEPROP 1 LAST OFFPAGE TRUE
J 2
(-6450 4250);
DISPLAY 0.872340 (-6450 4250);
PAINT GREEN (-6450 4250);
DISPLAY INVISIBLE (-6450 4250);
FORCEPROP 1 LAST COMMENT_BODY TRUE
J 2
(-6100 4275);
DISPLAY 0.872340 (-6100 4275);
PAINT GREEN (-6100 4275);
DISPLAY INVISIBLE (-6100 4275);
FORCEPROP 2 LAST PATH I12
J 0
(-6075 4450);
DISPLAY 1.021277 (-6075 4450);
DISPLAY INVISIBLE (-6075 4450);
FORCEADD OFFPAGE..4
R 2
(-6125 4275);
FORCEPROP 2 LAST $XR1 173 
J 0
(-6496 4275);
DISPLAY 0.638298 (-6496 4275);
PAINT MONO (-6496 4275);
FORCEPROP 2 LAST $XR0 27 
J 0
(-6376 4275);
DISPLAY 0.638298 (-6376 4275);
PAINT MONO (-6376 4275);
FORCEPROP 2 LAST CDS_LIB standard
J 0
(-6125 4275);
DISPLAY INVISIBLE (-6125 4275);
FORCEPROP 1 LAST OFFPAGE TRUE
J 2
(-6450 4150);
DISPLAY 0.872340 (-6450 4150);
PAINT GREEN (-6450 4150);
DISPLAY INVISIBLE (-6450 4150);
FORCEPROP 1 LAST COMMENT_BODY TRUE
J 2
(-6100 4175);
DISPLAY 0.872340 (-6100 4175);
PAINT GREEN (-6100 4175);
DISPLAY INVISIBLE (-6100 4175);
FORCEPROP 2 LAST PATH I13
J 0
(-6075 4350);
DISPLAY 1.021277 (-6075 4350);
DISPLAY INVISIBLE (-6075 4350);
FORCEADD OFFPAGE..4
R 2
(-6125 4525);
FORCEPROP 2 LAST $XR1 174 
J 0
(-6496 4525);
DISPLAY 0.638298 (-6496 4525);
PAINT MONO (-6496 4525);
FORCEPROP 2 LAST $XR0 27 
J 0
(-6376 4525);
DISPLAY 0.638298 (-6376 4525);
PAINT MONO (-6376 4525);
FORCEPROP 2 LAST CDS_LIB standard
J 0
(-6125 4525);
DISPLAY INVISIBLE (-6125 4525);
FORCEPROP 1 LAST OFFPAGE TRUE
J 2
(-6450 4400);
DISPLAY 0.872340 (-6450 4400);
PAINT GREEN (-6450 4400);
DISPLAY INVISIBLE (-6450 4400);
FORCEPROP 1 LAST COMMENT_BODY TRUE
J 2
(-6100 4425);
DISPLAY 0.872340 (-6100 4425);
PAINT GREEN (-6100 4425);
DISPLAY INVISIBLE (-6100 4425);
FORCEPROP 2 LAST PATH I14
J 0
(-6075 4600);
DISPLAY 1.021277 (-6075 4600);
DISPLAY INVISIBLE (-6075 4600);
FORCEADD OFFPAGE..2
R 2
(-6575 4575);
FORCEPROP 2 LAST $XR1 174 
J 0
(-6919 4575);
DISPLAY 0.638298 (-6919 4575);
PAINT MONO (-6919 4575);
FORCEPROP 2 LAST $XR0 27 
J 0
(-6799 4575);
DISPLAY 0.638298 (-6799 4575);
PAINT MONO (-6799 4575);
FORCEPROP 2 LAST CDS_LIB standard
J 2
(-6575 4575);
DISPLAY INVISIBLE (-6575 4575);
FORCEPROP 1 LAST OFFPAGE TRUE
J 2
(-6900 4450);
DISPLAY 0.872340 (-6900 4450);
PAINT GREEN (-6900 4450);
DISPLAY INVISIBLE (-6900 4450);
FORCEPROP 1 LAST COMMENT_BODY TRUE
J 2
(-6530 4480);
DISPLAY 0.872340 (-6530 4480);
PAINT GREEN (-6530 4480);
DISPLAY INVISIBLE (-6530 4480);
FORCEPROP 2 LAST PATH I169
J 0
(-6775 4625);
DISPLAY 1.021277 (-6775 4625);
DISPLAY INVISIBLE (-6775 4625);
FORCEADD Q_RES..1
R 2
(-5725 4575);
FORCEPROP 1 LAST LOCATION R404
J 2
(-5825 4575);
DISPLAY 0.489362 (-5825 4575);
PAINT SKYBLUE (-5825 4575);
FORCEPROP 0 LAST $SEC 1
J 0
(-5825 4625);
DISPLAY 0.680851 (-5825 4625);
PAINT MONO (-5825 4625);
DISPLAY INVISIBLE (-5825 4625);
FORCEPROP 0 LAST CDS_SEC 1
J 0
(-5825 4625);
DISPLAY 1.021277 (-5825 4625);
DISPLAY INVISIBLE (-5825 4625);
FORCEPROP 1 LASTPIN (-5625 4575) $PN 1
J 2
(-5637 4587);
DISPLAY 0.489362 (-5637 4587);
PAINT MONO (-5637 4587);
FORCEPROP 1 LASTPIN (-5825 4575) $PN 2
J 2
(-5787 4587);
DISPLAY 0.489362 (-5787 4587);
PAINT MONO (-5787 4587);
FORCEPROP 1 LAST VALUE 0
J 0
(-5625 4575);
DISPLAY 0.489362 (-5625 4575);
PAINT SKYBLUE (-5625 4575);
FORCEPROP 2 LAST CDS_LIB pure_quanta
J 0
(-5725 4575);
DISPLAY INVISIBLE (-5725 4575);
FORCEPROP 1 LAST WATTAGE 1/16W
J 0
(-6125 4500);
DISPLAY 0.489362 (-6125 4500);
PAINT SKYBLUE (-6125 4500);
DISPLAY INVISIBLE (-6125 4500);
FORCEPROP 1 LAST MATERIAL CHIP
J 2
(-6150 4500);
DISPLAY 0.489362 (-6150 4500);
PAINT SKYBLUE (-6150 4500);
DISPLAY INVISIBLE (-6150 4500);
FORCEPROP 1 LAST TOLERANCE 5%
J 2
(-5700 4500);
DISPLAY 0.489362 (-5700 4500);
PAINT SKYBLUE (-5700 4500);
DISPLAY INVISIBLE (-5700 4500);
FORCEPROP 1 LAST PACK_TYPE 0402LF
J 2
(-5775 4500);
DISPLAY 0.489362 (-5775 4500);
PAINT SKYBLUE (-5775 4500);
DISPLAY INVISIBLE (-5775 4500);
FORCEPROP 1 LAST PATH I170
J 2
(-5675 4725);
DISPLAY 0.978723 (-5675 4725);
PAINT WHITE (-5675 4725);
DISPLAY INVISIBLE (-5675 4725);
FORCEPROP 1 LAST PART_NUMBER CS00002JB13
J 2
(-5750 4625);
DISPLAY 0.489362 (-5750 4625);
PAINT SKYBLUE (-5750 4625);
DISPLAY INVISIBLE (-5750 4625);
FORCEADD OFFPAGE..2
R 2
(-6125 2425);
FORCEPROP 2 LAST $XR1 82 
J 0
(-6439 2425);
DISPLAY 0.638298 (-6439 2425);
PAINT MONO (-6439 2425);
FORCEPROP 2 LAST $XR0 27 
J 0
(-6349 2425);
DISPLAY 0.638298 (-6349 2425);
PAINT MONO (-6349 2425);
FORCEPROP 2 LAST CDS_LIB standard
J 0
(-6125 2425);
DISPLAY INVISIBLE (-6125 2425);
FORCEPROP 1 LAST OFFPAGE TRUE
J 2
(-6450 2300);
DISPLAY 0.872340 (-6450 2300);
PAINT GREEN (-6450 2300);
DISPLAY INVISIBLE (-6450 2300);
FORCEPROP 1 LAST COMMENT_BODY TRUE
J 2
(-6080 2330);
DISPLAY 0.872340 (-6080 2330);
PAINT GREEN (-6080 2330);
DISPLAY INVISIBLE (-6080 2330);
FORCEPROP 2 LAST PATH I191
J 0
(-6325 2475);
DISPLAY 1.021277 (-6325 2475);
DISPLAY INVISIBLE (-6325 2475);
FORCEADD GENOA_SP5..20
(-4275 3500);
FORCEPROP 1 LAST LOCATION U25
J 0
(-4870 6231);
DISPLAY 0.489362 (-4870 6231);
PAINT SKYBLUE (-4870 6231);
FORCEPROP 0 LAST $SEC 20
J 0
(-4850 6375);
DISPLAY 0.680851 (-4850 6375);
PAINT MONO (-4850 6375);
DISPLAY INVISIBLE (-4850 6375);
FORCEPROP 0 LAST CDS_SEC 20
J 0
(-4850 6375);
DISPLAY 1.021277 (-4850 6375);
DISPLAY INVISIBLE (-4850 6375);
FORCEPROP 0 LASTPIN (-3525 4875) $PN A68
J 0
(-3515 4885);
DISPLAY 0.489362 (-3515 4885);
PAINT MONO (-3515 4885);
FORCEPROP 0 LASTPIN (-3525 5775) $PN C32
J 0
(-3515 5785);
DISPLAY 0.489362 (-3515 5785);
PAINT MONO (-3515 5785);
FORCEPROP 0 LASTPIN (-3525 5725) $PN A34
J 0
(-3515 5735);
DISPLAY 0.489362 (-3515 5735);
PAINT MONO (-3515 5735);
FORCEPROP 0 LASTPIN (-3525 5675) $PN C33
J 0
(-3515 5685);
DISPLAY 0.489362 (-3515 5685);
PAINT MONO (-3515 5685);
FORCEPROP 0 LASTPIN (-3525 5625) $PN D33
J 0
(-3515 5635);
DISPLAY 0.489362 (-3515 5635);
PAINT MONO (-3515 5635);
FORCEPROP 0 LASTPIN (-3525 5575) $PN A33
J 0
(-3515 5585);
DISPLAY 0.489362 (-3515 5585);
PAINT MONO (-3515 5585);
FORCEPROP 0 LASTPIN (-3525 5525) $PN A32
J 0
(-3515 5535);
DISPLAY 0.489362 (-3515 5535);
PAINT MONO (-3515 5535);
FORCEPROP 0 LASTPIN (-3525 5475) $PN D32
J 0
(-3515 5485);
DISPLAY 0.489362 (-3515 5485);
PAINT MONO (-3515 5485);
FORCEPROP 0 LASTPIN (-3525 4225) $PN C63
J 0
(-3515 4235);
DISPLAY 0.489362 (-3515 4235);
PAINT MONO (-3515 4235);
FORCEPROP 0 LASTPIN (-3525 4175) $PN C62
J 0
(-3515 4185);
DISPLAY 0.489362 (-3515 4185);
PAINT MONO (-3515 4185);
FORCEPROP 0 LASTPIN (-3525 4125) $PN A63
J 0
(-3515 4135);
DISPLAY 0.489362 (-3515 4135);
PAINT MONO (-3515 4135);
FORCEPROP 0 LASTPIN (-3525 4075) $PN A62
J 0
(-3515 4085);
DISPLAY 0.489362 (-3515 4085);
PAINT MONO (-3515 4085);
FORCEPROP 0 LASTPIN (-5025 2525) $PN C70
J 2
(-5035 2535);
DISPLAY 0.489362 (-5035 2535);
PAINT MONO (-5035 2535);
FORCEPROP 0 LASTPIN (-5025 2475) $PN B69
J 2
(-5035 2485);
DISPLAY 0.489362 (-5035 2485);
PAINT MONO (-5035 2485);
FORCEPROP 0 LASTPIN (-5025 2425) $PN D68
J 2
(-5035 2435);
DISPLAY 0.489362 (-5035 2435);
PAINT MONO (-5035 2435);
FORCEPROP 0 LASTPIN (-5025 3075) $PN B66
J 2
(-5035 3085);
DISPLAY 0.489362 (-5035 3085);
PAINT MONO (-5035 3085);
FORCEPROP 0 LASTPIN (-5025 4275) $PN C16
J 2
(-5035 4285);
DISPLAY 0.489362 (-5035 4285);
PAINT MONO (-5035 4285);
FORCEPROP 0 LASTPIN (-5025 5675) $PN C22
J 2
(-5035 5685);
DISPLAY 0.489362 (-5035 5685);
PAINT MONO (-5035 5685);
FORCEPROP 0 LASTPIN (-5025 5625) $PN DG72
J 2
(-5035 5635);
DISPLAY 0.489362 (-5035 5635);
PAINT MONO (-5035 5635);
FORCEPROP 0 LASTPIN (-3525 4775) $PN A69
J 0
(-3515 4785);
DISPLAY 0.489362 (-3515 4785);
PAINT MONO (-3515 4785);
FORCEPROP 0 LASTPIN (-5025 1125) $PN DH8
J 2
(-5035 1135);
DISPLAY 0.489362 (-5035 1135);
PAINT MONO (-5035 1135);
FORCEPROP 0 LASTPIN (-5025 2975) $PN DJ55
J 2
(-5035 2985);
DISPLAY 0.489362 (-5035 2985);
PAINT MONO (-5035 2985);
FORCEPROP 0 LASTPIN (-5025 2925) $PN DJ56
J 2
(-5035 2935);
DISPLAY 0.489362 (-5035 2935);
PAINT MONO (-5035 2935);
FORCEPROP 0 LASTPIN (-5025 4875) $PN DJ71
J 2
(-5035 4885);
DISPLAY 0.489362 (-5035 4885);
PAINT MONO (-5035 4885);
FORCEPROP 0 LASTPIN (-5025 4825) $PN DH71
J 2
(-5035 4835);
DISPLAY 0.489362 (-5035 4835);
PAINT MONO (-5035 4835);
FORCEPROP 0 LASTPIN (-5025 2775) $PN C19
J 2
(-5035 2785);
DISPLAY 0.489362 (-5035 2785);
PAINT MONO (-5035 2785);
FORCEPROP 0 LASTPIN (-5025 2725) $PN C68
J 2
(-5035 2735);
DISPLAY 0.489362 (-5035 2735);
PAINT MONO (-5035 2735);
FORCEPROP 0 LASTPIN (-5025 2675) $PN DH73
J 2
(-5035 2685);
DISPLAY 0.489362 (-5035 2685);
PAINT MONO (-5035 2685);
FORCEPROP 0 LASTPIN (-5025 2625) $PN DH10
J 2
(-5035 2635);
DISPLAY 0.489362 (-5035 2635);
PAINT MONO (-5035 2635);
FORCEPROP 0 LASTPIN (-5025 5525) $PN A23
J 2
(-5035 5535);
DISPLAY 0.489362 (-5035 5535);
PAINT MONO (-5035 5535);
FORCEPROP 0 LASTPIN (-5025 5325) $PN DJ72
J 2
(-5035 5335);
DISPLAY 0.489362 (-5035 5335);
PAINT MONO (-5035 5335);
FORCEPROP 0 LASTPIN (-5025 5475) $PN A22
J 2
(-5035 5485);
DISPLAY 0.489362 (-5035 5485);
PAINT MONO (-5035 5485);
FORCEPROP 0 LASTPIN (-5025 5275) $PN DH72
J 2
(-5035 5285);
DISPLAY 0.489362 (-5035 5285);
PAINT MONO (-5035 5285);
FORCEPROP 0 LASTPIN (-5025 5425) $PN B21
J 2
(-5035 5435);
DISPLAY 0.489362 (-5035 5435);
PAINT MONO (-5035 5435);
FORCEPROP 0 LASTPIN (-5025 5225) $PN DG73
J 2
(-5035 5235);
DISPLAY 0.489362 (-5035 5235);
PAINT MONO (-5035 5235);
FORCEPROP 0 LASTPIN (-5025 4425) $PN B17
J 2
(-5035 4435);
DISPLAY 0.489362 (-5035 4435);
PAINT MONO (-5035 4435);
FORCEPROP 0 LASTPIN (-5025 4525) $PN C17
J 2
(-5035 4535);
DISPLAY 0.489362 (-5035 4535);
PAINT MONO (-5035 4535);
FORCEPROP 0 LASTPIN (-5025 4575) $PN C18
J 2
(-5035 4585);
DISPLAY 0.489362 (-5035 4585);
PAINT MONO (-5035 4585);
FORCEPROP 0 LASTPIN (-3525 3125) $PN AA50
J 0
(-3515 3135);
DISPLAY 0.489362 (-3515 3135);
PAINT MONO (-3515 3135);
FORCEPROP 0 LASTPIN (-3525 3075) $PN CJ28
J 0
(-3515 3085);
DISPLAY 0.489362 (-3515 3085);
PAINT MONO (-3515 3085);
FORCEPROP 0 LASTPIN (-3525 3025) $PN CJ48
J 0
(-3515 3035);
DISPLAY 0.489362 (-3515 3035);
PAINT MONO (-3515 3035);
FORCEPROP 0 LASTPIN (-3525 2975) $PN AA30
J 0
(-3515 2985);
DISPLAY 0.489362 (-3515 2985);
PAINT MONO (-3515 2985);
FORCEPROP 0 LASTPIN (-3525 2925) $PN AA52
J 0
(-3515 2935);
DISPLAY 0.489362 (-3515 2935);
PAINT MONO (-3515 2935);
FORCEPROP 0 LASTPIN (-3525 2875) $PN CJ26
J 0
(-3515 2885);
DISPLAY 0.489362 (-3515 2885);
PAINT MONO (-3515 2885);
FORCEPROP 0 LASTPIN (-3525 2825) $PN CJ50
J 0
(-3515 2835);
DISPLAY 0.489362 (-3515 2835);
PAINT MONO (-3515 2835);
FORCEPROP 0 LASTPIN (-3525 2775) $PN AA27
J 0
(-3515 2785);
DISPLAY 0.489362 (-3515 2785);
PAINT MONO (-3515 2785);
FORCEPROP 0 LASTPIN (-3525 2725) $PN AA48
J 0
(-3515 2735);
DISPLAY 0.489362 (-3515 2735);
PAINT MONO (-3515 2735);
FORCEPROP 0 LASTPIN (-3525 2675) $PN CK30
J 0
(-3515 2685);
DISPLAY 0.489362 (-3515 2685);
PAINT MONO (-3515 2685);
FORCEPROP 0 LASTPIN (-3525 2625) $PN CJ47
J 0
(-3515 2635);
DISPLAY 0.489362 (-3515 2635);
PAINT MONO (-3515 2635);
FORCEPROP 0 LASTPIN (-3525 2575) $PN AA28
J 0
(-3515 2585);
DISPLAY 0.489362 (-3515 2585);
PAINT MONO (-3515 2585);
FORCEPROP 0 LASTPIN (-3525 1825) $PN AA25
J 0
(-3515 1835);
DISPLAY 0.489362 (-3515 1835);
PAINT MONO (-3515 1835);
FORCEPROP 0 LASTPIN (-3525 2475) $PN AA51
J 0
(-3515 2485);
DISPLAY 0.489362 (-3515 2485);
PAINT MONO (-3515 2485);
FORCEPROP 0 LASTPIN (-3525 2425) $PN CJ27
J 0
(-3515 2435);
DISPLAY 0.489362 (-3515 2435);
PAINT MONO (-3515 2435);
FORCEPROP 0 LASTPIN (-3525 2375) $PN CJ49
J 0
(-3515 2385);
DISPLAY 0.489362 (-3515 2385);
PAINT MONO (-3515 2385);
FORCEPROP 0 LASTPIN (-3525 2325) $PN Y30
J 0
(-3515 2335);
DISPLAY 0.489362 (-3515 2335);
PAINT MONO (-3515 2335);
FORCEPROP 0 LASTPIN (-3525 2275) $PN AA53
J 0
(-3515 2285);
DISPLAY 0.489362 (-3515 2285);
PAINT MONO (-3515 2285);
FORCEPROP 0 LASTPIN (-3525 2225) $PN CJ25
J 0
(-3515 2235);
DISPLAY 0.489362 (-3515 2235);
PAINT MONO (-3515 2235);
FORCEPROP 0 LASTPIN (-3525 2175) $PN CJ51
J 0
(-3515 2185);
DISPLAY 0.489362 (-3515 2185);
PAINT MONO (-3515 2185);
FORCEPROP 0 LASTPIN (-3525 2125) $PN AA26
J 0
(-3515 2135);
DISPLAY 0.489362 (-3515 2135);
PAINT MONO (-3515 2135);
FORCEPROP 0 LASTPIN (-3525 2075) $PN Y47
J 0
(-3515 2085);
DISPLAY 0.489362 (-3515 2085);
PAINT MONO (-3515 2085);
FORCEPROP 0 LASTPIN (-3525 2025) $PN CK29
J 0
(-3515 2035);
DISPLAY 0.489362 (-3515 2035);
PAINT MONO (-3515 2035);
FORCEPROP 0 LASTPIN (-3525 1975) $PN CK47
J 0
(-3515 1985);
DISPLAY 0.489362 (-3515 1985);
PAINT MONO (-3515 1985);
FORCEPROP 0 LASTPIN (-3525 1925) $PN Y29
J 0
(-3515 1935);
DISPLAY 0.489362 (-3515 1935);
PAINT MONO (-3515 1935);
FORCEPROP 0 LASTPIN (-3525 1725) $PN AA24
J 0
(-3515 1735);
DISPLAY 0.489362 (-3515 1735);
PAINT MONO (-3515 1735);
FORCEPROP 0 LASTPIN (-3525 3875) $PN AA46
J 0
(-3515 3885);
DISPLAY 0.489362 (-3515 3885);
PAINT MONO (-3515 3885);
FORCEPROP 0 LASTPIN (-3525 3825) $PN CJ30
J 0
(-3515 3835);
DISPLAY 0.489362 (-3515 3835);
PAINT MONO (-3515 3835);
FORCEPROP 0 LASTPIN (-3525 3775) $PN CJ46
J 0
(-3515 3785);
DISPLAY 0.489362 (-3515 3785);
PAINT MONO (-3515 3785);
FORCEPROP 0 LASTPIN (-3525 3725) $PN Y46
J 0
(-3515 3735);
DISPLAY 0.489362 (-3515 3735);
PAINT MONO (-3515 3735);
FORCEPROP 0 LASTPIN (-3525 3225) $PN AA49
J 0
(-3515 3235);
DISPLAY 0.489362 (-3515 3235);
PAINT MONO (-3515 3235);
FORCEPROP 0 LASTPIN (-3525 3575) $PN AA47
J 0
(-3515 3585);
DISPLAY 0.489362 (-3515 3585);
PAINT MONO (-3515 3585);
FORCEPROP 0 LASTPIN (-3525 3525) $PN CJ29
J 0
(-3515 3535);
DISPLAY 0.489362 (-3515 3535);
PAINT MONO (-3515 3535);
FORCEPROP 0 LASTPIN (-3525 3475) $PN AA29
J 0
(-3515 3485);
DISPLAY 0.489362 (-3515 3485);
PAINT MONO (-3515 3485);
FORCEPROP 0 LASTPIN (-3525 3425) $PN CJ52
J 0
(-3515 3435);
DISPLAY 0.489362 (-3515 3435);
PAINT MONO (-3515 3435);
FORCEPROP 0 LASTPIN (-3525 3375) $PN AA23
J 0
(-3515 3385);
DISPLAY 0.489362 (-3515 3385);
PAINT MONO (-3515 3385);
FORCEPROP 0 LASTPIN (-3525 3325) $PN CJ53
J 0
(-3515 3335);
DISPLAY 0.489362 (-3515 3335);
PAINT MONO (-3515 3335);
FORCEPROP 0 LASTPIN (-3525 1125) $PN W31
J 0
(-3515 1135);
DISPLAY 0.489362 (-3515 1135);
PAINT MONO (-3515 1135);
FORCEPROP 0 LASTPIN (-5025 3825) $PN B60
J 2
(-5035 3835);
DISPLAY 0.489362 (-5035 3835);
PAINT MONO (-5035 3835);
FORCEPROP 0 LASTPIN (-5025 3775) $PN CJ24
J 2
(-5035 3785);
DISPLAY 0.489362 (-5035 3785);
PAINT MONO (-5035 3785);
FORCEPROP 0 LASTPIN (-5025 3725) $PN CK46
J 2
(-5035 3735);
DISPLAY 0.489362 (-5035 3735);
PAINT MONO (-5035 3735);
FORCEPROP 0 LASTPIN (-5025 3675) $PN E32
J 2
(-5035 3685);
DISPLAY 0.489362 (-5035 3685);
PAINT MONO (-5035 3685);
FORCEPROP 0 LASTPIN (-5025 3575) $PN B58
J 2
(-5035 3585);
DISPLAY 0.489362 (-5035 3585);
PAINT MONO (-5035 3585);
FORCEPROP 0 LASTPIN (-5025 3525) $PN D7
J 2
(-5035 3535);
DISPLAY 0.489362 (-5035 3535);
PAINT MONO (-5035 3535);
FORCEPROP 0 LASTPIN (-5025 3225) $PN B61
J 2
(-5035 3235);
DISPLAY 0.489362 (-5035 3235);
PAINT MONO (-5035 3235);
FORCEPROP 0 LASTPIN (-3525 4725) $PN DJ9
J 0
(-3515 4735);
DISPLAY 0.489362 (-3515 4735);
PAINT MONO (-3515 4735);
FORCEPROP 0 LASTPIN (-5025 4375) $PN A16
J 2
(-5035 4385);
DISPLAY 0.489362 (-5035 4385);
PAINT MONO (-5035 4385);
FORCEPROP 0 LASTPIN (-5025 4475) $PN A17
J 2
(-5035 4485);
DISPLAY 0.489362 (-5035 4485);
PAINT MONO (-5035 4485);
FORCEPROP 0 LASTPIN (-3525 1625) $PN DJ33
J 0
(-3515 1635);
DISPLAY 0.489362 (-3515 1635);
PAINT MONO (-3515 1635);
FORCEPROP 0 LASTPIN (-3525 1525) $PN DG34
J 0
(-3515 1535);
DISPLAY 0.489362 (-3515 1535);
PAINT MONO (-3515 1535);
FORCEPROP 0 LASTPIN (-3525 1575) $PN DF34
J 0
(-3515 1585);
DISPLAY 0.489362 (-3515 1585);
PAINT MONO (-3515 1585);
FORCEPROP 0 LASTPIN (-3525 1425) $PN DG35
J 0
(-3515 1435);
DISPLAY 0.489362 (-3515 1435);
PAINT MONO (-3515 1435);
FORCEPROP 0 LASTPIN (-3525 1475) $PN DJ34
J 0
(-3515 1485);
DISPLAY 0.489362 (-3515 1485);
PAINT MONO (-3515 1485);
FORCEPROP 0 LASTPIN (-3525 1325) $PN DH33
J 0
(-3515 1335);
DISPLAY 0.489362 (-3515 1335);
PAINT MONO (-3515 1335);
FORCEPROP 0 LASTPIN (-3525 1375) $PN DJ32
J 0
(-3515 1385);
DISPLAY 0.489362 (-3515 1385);
PAINT MONO (-3515 1385);
FORCEPROP 0 LASTPIN (-5025 1925) $PN DH3
J 2
(-5035 1935);
DISPLAY 0.489362 (-5035 1935);
PAINT MONO (-5035 1935);
FORCEPROP 0 LASTPIN (-5025 1825) $PN C74
J 2
(-5035 1835);
DISPLAY 0.489362 (-5035 1835);
PAINT MONO (-5035 1835);
FORCEPROP 0 LASTPIN (-5025 1875) $PN BP53
J 2
(-5035 1885);
DISPLAY 0.489362 (-5035 1885);
PAINT MONO (-5035 1885);
FORCEPROP 0 LASTPIN (-5025 1975) $PN C2
J 2
(-5035 1985);
DISPLAY 0.489362 (-5035 1985);
PAINT MONO (-5035 1985);
FORCEPROP 0 LASTPIN (-5025 2025) $PN DG3
J 2
(-5035 2035);
DISPLAY 0.489362 (-5035 2035);
PAINT MONO (-5035 2035);
FORCEPROP 0 LASTPIN (-5025 1775) $PN B3
J 2
(-5035 1785);
DISPLAY 0.489362 (-5035 1785);
PAINT MONO (-5035 1785);
FORCEPROP 0 LASTPIN (-5025 2075) $PN BR53
J 2
(-5035 2085);
DISPLAY 0.489362 (-5035 2085);
PAINT MONO (-5035 2085);
FORCEPROP 0 LASTPIN (-5025 2325) $PN C3
J 2
(-5035 2335);
DISPLAY 0.489362 (-5035 2335);
PAINT MONO (-5035 2335);
FORCEPROP 0 LASTPIN (-5025 2275) $PN BR54
J 2
(-5035 2285);
DISPLAY 0.489362 (-5035 2285);
PAINT MONO (-5035 2285);
FORCEPROP 0 LASTPIN (-5025 2225) $PN DJ3
J 2
(-5035 2235);
DISPLAY 0.489362 (-5035 2235);
PAINT MONO (-5035 2235);
FORCEPROP 0 LASTPIN (-5025 2175) $PN B73
J 2
(-5035 2185);
DISPLAY 0.489362 (-5035 2185);
PAINT MONO (-5035 2185);
FORCEPROP 0 LASTPIN (-3525 4575) $PN C66
J 0
(-3515 4585);
DISPLAY 0.489362 (-3515 4585);
PAINT MONO (-3515 4585);
FORCEPROP 0 LASTPIN (-3525 4525) $PN C65
J 0
(-3515 4535);
DISPLAY 0.489362 (-3515 4535);
PAINT MONO (-3515 4535);
FORCEPROP 0 LASTPIN (-3525 4475) $PN A66
J 0
(-3515 4485);
DISPLAY 0.489362 (-3515 4485);
PAINT MONO (-3515 4485);
FORCEPROP 0 LASTPIN (-3525 4425) $PN A65
J 0
(-3515 4435);
DISPLAY 0.489362 (-3515 4435);
PAINT MONO (-3515 4435);
FORCEPROP 2 LAST VALUE SOCKET6096_13568-001
J 0
(-4850 6275);
DISPLAY 0.489362 (-4850 6275);
PAINT SKYBLUE (-4850 6275);
FORCEPROP 1 LAST MATERIAL IO
J 0
(-4870 5957);
DISPLAY 0.489362 (-4870 5957);
PAINT SKYBLUE (-4870 5957);
FORCEPROP 2 LAST PART_TYPE SMLF
J 0
(-4850 6325);
DISPLAY 1.021277 (-4850 6325);
FORCEPROP 1 LAST NEEDS_NO_SIZE TRUE
J 0
(-4275 3500);
DISPLAY 0.723404 (-4275 3500);
PAINT GREEN (-4275 3500);
DISPLAY INVISIBLE (-4275 3500);
FORCEPROP 1 LAST CDS_LMAN_SYM_OUTLINE -600,2425,600,-2425
J 0
(-4275 3500);
DISPLAY 0.468085 (-4275 3500);
PAINT GREEN (-4275 3500);
DISPLAY INVISIBLE (-4275 3500);
FORCEPROP 2 LAST CDS_LIB pure_quanta
J 0
(-4275 3500);
DISPLAY INVISIBLE (-4275 3500);
FORCEPROP 1 LAST PATH I227
J 0
(-4275 3500);
DISPLAY 0.723404 (-4275 3500);
PAINT GREEN (-4275 3500);
DISPLAY INVISIBLE (-4275 3500);
FORCEPROP 1 LAST PART_NUMBER DGA^6000030
J 0
(-4870 6084);
DISPLAY 0.489362 (-4870 6084);
PAINT SKYBLUE (-4870 6084);
DISPLAY INVISIBLE (-4870 6084);
FORCEADD UNIVERSAL_POWER..1
(-225 5925);
FORCEPROP 3 LASTPIN (-225 5875) SIG_NAME PVDD18_S5_P0\g
J 0
(-215 5885);
DISPLAY 0.659574 (-215 5885);
PAINT MONO (-215 5885);
DISPLAY INVISIBLE (-215 5885);
FORCEPROP 1 LAST HDL_POWER PVDD18_S5_P0
J 1
(-225 5975);
DISPLAY 0.489362 (-225 5975);
PAINT GREEN (-225 5975);
FORCEPROP 2 LAST CDS_LIB pure_quanta_power
J 0
(-225 5925);
DISPLAY INVISIBLE (-225 5925);
FORCEPROP 1 LAST PATH I231
J 0
(-175 5950);
DISPLAY 0.872340 (-175 5950);
PAINT AQUA (-175 5950);
DISPLAY INVISIBLE (-175 5950);
FORCEADD OFFPAGE..2
R 2
(-1525 5550);
FORCEPROP 2 LAST $XR0 27 
J 0
(-1779 5550);
DISPLAY 0.638298 (-1779 5550);
PAINT MONO (-1779 5550);
FORCEPROP 2 LAST CDS_LIB standard
J 0
(-1525 5550);
DISPLAY INVISIBLE (-1525 5550);
FORCEPROP 1 LAST OFFPAGE TRUE
J 2
(-1850 5425);
DISPLAY 0.872340 (-1850 5425);
PAINT GREEN (-1850 5425);
DISPLAY INVISIBLE (-1850 5425);
FORCEPROP 1 LAST COMMENT_BODY TRUE
J 2
(-1480 5455);
DISPLAY 0.872340 (-1480 5455);
PAINT PEACH (-1480 5455);
DISPLAY INVISIBLE (-1480 5455);
FORCEPROP 2 LAST PATH I245
J 0
(-1725 5600);
DISPLAY 1.021277 (-1725 5600);
DISPLAY INVISIBLE (-1725 5600);
FORCEADD OFFPAGE..2
R 2
(-1525 5600);
FORCEPROP 2 LAST $XR0 27 
J 0
(-1779 5600);
DISPLAY 0.638298 (-1779 5600);
PAINT MONO (-1779 5600);
FORCEPROP 2 LAST CDS_LIB standard
J 0
(-1525 5600);
DISPLAY INVISIBLE (-1525 5600);
FORCEPROP 1 LAST OFFPAGE TRUE
J 2
(-1850 5475);
DISPLAY 0.872340 (-1850 5475);
PAINT GREEN (-1850 5475);
DISPLAY INVISIBLE (-1850 5475);
FORCEPROP 1 LAST COMMENT_BODY TRUE
J 2
(-1480 5505);
DISPLAY 0.872340 (-1480 5505);
PAINT PEACH (-1480 5505);
DISPLAY INVISIBLE (-1480 5505);
FORCEPROP 2 LAST PATH I246
J 0
(-1725 5650);
DISPLAY 1.021277 (-1725 5650);
DISPLAY INVISIBLE (-1725 5650);
FORCEADD OFFPAGE..2
R 2
(-1525 5500);
FORCEPROP 2 LAST $XR0 27 
J 0
(-1779 5500);
DISPLAY 0.638298 (-1779 5500);
PAINT MONO (-1779 5500);
FORCEPROP 2 LAST CDS_LIB standard
J 0
(-1525 5500);
DISPLAY INVISIBLE (-1525 5500);
FORCEPROP 1 LAST OFFPAGE TRUE
J 2
(-1850 5375);
DISPLAY 0.872340 (-1850 5375);
PAINT GREEN (-1850 5375);
DISPLAY INVISIBLE (-1850 5375);
FORCEPROP 1 LAST COMMENT_BODY TRUE
J 2
(-1480 5405);
DISPLAY 0.872340 (-1480 5405);
PAINT PEACH (-1480 5405);
DISPLAY INVISIBLE (-1480 5405);
FORCEPROP 2 LAST PATH I247
J 0
(-1725 5550);
DISPLAY 1.021277 (-1725 5550);
DISPLAY INVISIBLE (-1725 5550);
FORCEADD OFFPAGE..2
R 2
(-1525 5450);
FORCEPROP 2 LAST $XR0 27 
J 0
(-1779 5450);
DISPLAY 0.638298 (-1779 5450);
PAINT MONO (-1779 5450);
FORCEPROP 2 LAST CDS_LIB standard
J 0
(-1525 5450);
DISPLAY INVISIBLE (-1525 5450);
FORCEPROP 1 LAST OFFPAGE TRUE
J 2
(-1850 5325);
DISPLAY 0.872340 (-1850 5325);
PAINT GREEN (-1850 5325);
DISPLAY INVISIBLE (-1850 5325);
FORCEPROP 1 LAST COMMENT_BODY TRUE
J 2
(-1480 5355);
DISPLAY 0.872340 (-1480 5355);
PAINT PEACH (-1480 5355);
DISPLAY INVISIBLE (-1480 5355);
FORCEPROP 2 LAST PATH I248
J 0
(-1725 5500);
DISPLAY 1.021277 (-1725 5500);
DISPLAY INVISIBLE (-1725 5500);
FORCEADD OFFPAGE..2
R 2
(-1525 5400);
FORCEPROP 2 LAST $XR1 27 
J 0
(-1869 5400);
DISPLAY 0.638298 (-1869 5400);
PAINT MONO (-1869 5400);
FORCEPROP 2 LAST $XR0 82 
J 0
(-1779 5400);
DISPLAY 0.638298 (-1779 5400);
PAINT MONO (-1779 5400);
FORCEPROP 2 LAST CDS_LIB standard
J 0
(-1525 5400);
DISPLAY INVISIBLE (-1525 5400);
FORCEPROP 1 LAST OFFPAGE TRUE
J 2
(-1850 5275);
DISPLAY 0.872340 (-1850 5275);
PAINT GREEN (-1850 5275);
DISPLAY INVISIBLE (-1850 5275);
FORCEPROP 1 LAST COMMENT_BODY TRUE
J 2
(-1480 5305);
DISPLAY 0.872340 (-1480 5305);
PAINT PEACH (-1480 5305);
DISPLAY INVISIBLE (-1480 5305);
FORCEPROP 2 LAST PATH I249
J 0
(-1725 5450);
DISPLAY 1.021277 (-1725 5450);
DISPLAY INVISIBLE (-1725 5450);
FORCEADD OFFPAGE..2
R 2
(-1525 5300);
FORCEPROP 2 LAST $XR2 172 
J 0
(-1989 5300);
DISPLAY 0.638298 (-1989 5300);
PAINT MONO (-1989 5300);
FORCEPROP 2 LAST $XR1 82 
J 0
(-1869 5300);
DISPLAY 0.638298 (-1869 5300);
PAINT MONO (-1869 5300);
FORCEPROP 2 LAST $XR0 27 
J 0
(-1779 5300);
DISPLAY 0.638298 (-1779 5300);
PAINT MONO (-1779 5300);
FORCEPROP 2 LAST CDS_LIB standard
J 0
(-1525 5300);
DISPLAY INVISIBLE (-1525 5300);
FORCEPROP 1 LAST OFFPAGE TRUE
J 2
(-1850 5175);
DISPLAY 0.872340 (-1850 5175);
PAINT GREEN (-1850 5175);
DISPLAY INVISIBLE (-1850 5175);
FORCEPROP 1 LAST COMMENT_BODY TRUE
J 2
(-1480 5205);
DISPLAY 0.872340 (-1480 5205);
PAINT PEACH (-1480 5205);
DISPLAY INVISIBLE (-1480 5205);
FORCEPROP 2 LAST PATH I250
J 0
(-1725 5350);
DISPLAY 1.021277 (-1725 5350);
DISPLAY INVISIBLE (-1725 5350);
FORCEADD OFFPAGE..2
R 2
(-1525 5350);
FORCEPROP 2 LAST $XR1 82 
J 0
(-1869 5350);
DISPLAY 0.638298 (-1869 5350);
PAINT MONO (-1869 5350);
FORCEPROP 2 LAST $XR0 27 
J 0
(-1779 5350);
DISPLAY 0.638298 (-1779 5350);
PAINT MONO (-1779 5350);
FORCEPROP 2 LAST CDS_LIB standard
J 0
(-1525 5350);
DISPLAY INVISIBLE (-1525 5350);
FORCEPROP 1 LAST OFFPAGE TRUE
J 2
(-1850 5225);
DISPLAY 0.872340 (-1850 5225);
PAINT GREEN (-1850 5225);
DISPLAY INVISIBLE (-1850 5225);
FORCEPROP 1 LAST COMMENT_BODY TRUE
J 2
(-1480 5255);
DISPLAY 0.872340 (-1480 5255);
PAINT PEACH (-1480 5255);
DISPLAY INVISIBLE (-1480 5255);
FORCEPROP 2 LAST PATH I251
J 0
(-1725 5400);
DISPLAY 1.021277 (-1725 5400);
DISPLAY INVISIBLE (-1725 5400);
FORCEADD OFFPAGE..2
R 2
(-1525 5250);
FORCEPROP 2 LAST $XR2 172 
J 0
(-1989 5250);
DISPLAY 0.638298 (-1989 5250);
PAINT MONO (-1989 5250);
FORCEPROP 2 LAST $XR1 82 
J 0
(-1869 5250);
DISPLAY 0.638298 (-1869 5250);
PAINT MONO (-1869 5250);
FORCEPROP 2 LAST $XR0 27 
J 0
(-1779 5250);
DISPLAY 0.638298 (-1779 5250);
PAINT MONO (-1779 5250);
FORCEPROP 2 LAST CDS_LIB standard
J 0
(-1525 5250);
DISPLAY INVISIBLE (-1525 5250);
FORCEPROP 1 LAST OFFPAGE TRUE
J 2
(-1850 5125);
DISPLAY 0.872340 (-1850 5125);
PAINT GREEN (-1850 5125);
DISPLAY INVISIBLE (-1850 5125);
FORCEPROP 1 LAST COMMENT_BODY TRUE
J 2
(-1480 5155);
DISPLAY 0.872340 (-1480 5155);
PAINT PEACH (-1480 5155);
DISPLAY INVISIBLE (-1480 5155);
FORCEPROP 2 LAST PATH I252
J 0
(-1725 5300);
DISPLAY 1.021277 (-1725 5300);
DISPLAY INVISIBLE (-1725 5300);
FORCEADD OFFPAGE..2
R 2
(-1525 5200);
FORCEPROP 2 LAST $XR2 172 
J 0
(-1989 5200);
DISPLAY 0.638298 (-1989 5200);
PAINT MONO (-1989 5200);
FORCEPROP 2 LAST $XR1 82 
J 0
(-1869 5200);
DISPLAY 0.638298 (-1869 5200);
PAINT MONO (-1869 5200);
FORCEPROP 2 LAST $XR0 27 
J 0
(-1779 5200);
DISPLAY 0.638298 (-1779 5200);
PAINT MONO (-1779 5200);
FORCEPROP 2 LAST CDS_LIB standard
J 0
(-1525 5200);
DISPLAY INVISIBLE (-1525 5200);
FORCEPROP 1 LAST OFFPAGE TRUE
J 2
(-1850 5075);
DISPLAY 0.872340 (-1850 5075);
PAINT GREEN (-1850 5075);
DISPLAY INVISIBLE (-1850 5075);
FORCEPROP 1 LAST COMMENT_BODY TRUE
J 2
(-1480 5105);
DISPLAY 0.872340 (-1480 5105);
PAINT PEACH (-1480 5105);
DISPLAY INVISIBLE (-1480 5105);
FORCEPROP 2 LAST PATH I253
J 0
(-1725 5250);
DISPLAY 1.021277 (-1725 5250);
DISPLAY INVISIBLE (-1725 5250);
FORCEADD OFFPAGE..2
R 2
(-1525 5150);
FORCEPROP 2 LAST $XR0 27 
J 0
(-1779 5150);
DISPLAY 0.638298 (-1779 5150);
PAINT MONO (-1779 5150);
FORCEPROP 2 LAST CDS_LIB standard
J 0
(-1525 5150);
DISPLAY INVISIBLE (-1525 5150);
FORCEPROP 1 LAST OFFPAGE TRUE
J 2
(-1850 5025);
DISPLAY 0.872340 (-1850 5025);
PAINT GREEN (-1850 5025);
DISPLAY INVISIBLE (-1850 5025);
FORCEPROP 1 LAST COMMENT_BODY TRUE
J 2
(-1480 5055);
DISPLAY 0.872340 (-1480 5055);
PAINT PEACH (-1480 5055);
DISPLAY INVISIBLE (-1480 5055);
FORCEPROP 2 LAST PATH I254
J 0
(-1725 5200);
DISPLAY 1.021277 (-1725 5200);
DISPLAY INVISIBLE (-1725 5200);
FORCEADD OFFPAGE..2
R 2
(-1525 5100);
FORCEPROP 2 LAST $XR0 27 
J 0
(-1779 5100);
DISPLAY 0.638298 (-1779 5100);
PAINT MONO (-1779 5100);
FORCEPROP 2 LAST CDS_LIB standard
J 0
(-1525 5100);
DISPLAY INVISIBLE (-1525 5100);
FORCEPROP 1 LAST OFFPAGE TRUE
J 2
(-1850 4975);
DISPLAY 0.872340 (-1850 4975);
PAINT GREEN (-1850 4975);
DISPLAY INVISIBLE (-1850 4975);
FORCEPROP 1 LAST COMMENT_BODY TRUE
J 2
(-1480 5005);
DISPLAY 0.872340 (-1480 5005);
PAINT PEACH (-1480 5005);
DISPLAY INVISIBLE (-1480 5005);
FORCEPROP 2 LAST PATH I255
J 0
(-1725 5150);
DISPLAY 1.021277 (-1725 5150);
DISPLAY INVISIBLE (-1725 5150);
FORCEADD OFFPAGE..4
(-1975 4775);
FORCEPROP 2 LAST $XR1 82 
J 0
(-1699 4775);
DISPLAY 0.638298 (-1699 4775);
PAINT MONO (-1699 4775);
FORCEPROP 2 LAST $XR0 27 
J 0
(-1789 4775);
DISPLAY 0.638298 (-1789 4775);
PAINT MONO (-1789 4775);
FORCEPROP 2 LAST CDS_LIB standard
J 2
(-1975 4775);
DISPLAY INVISIBLE (-1975 4775);
FORCEPROP 1 LAST OFFPAGE TRUE
J 0
(-1650 4650);
DISPLAY 0.872340 (-1650 4650);
PAINT GREEN (-1650 4650);
DISPLAY INVISIBLE (-1650 4650);
FORCEPROP 1 LAST COMMENT_BODY TRUE
J 0
(-2000 4675);
DISPLAY 0.872340 (-2000 4675);
PAINT GREEN (-2000 4675);
DISPLAY INVISIBLE (-2000 4675);
FORCEPROP 2 LAST PATH I257
J 0
(-1675 4825);
DISPLAY 1.021277 (-1675 4825);
DISPLAY INVISIBLE (-1675 4825);
FORCEADD OFFPAGE..3
(-2650 4225);
FORCEPROP 2 LAST $XR0 27 
J 0
(-2436 4225);
DISPLAY 0.638298 (-2436 4225);
PAINT MONO (-2436 4225);
FORCEPROP 2 LAST CDS_LIB standard
J 0
(-2650 4225);
DISPLAY INVISIBLE (-2650 4225);
FORCEPROP 1 LAST OFFPAGE TRUE
J 0
(-2325 4100);
DISPLAY 0.872340 (-2325 4100);
PAINT GREEN (-2325 4100);
DISPLAY INVISIBLE (-2325 4100);
FORCEPROP 1 LAST COMMENT_BODY TRUE
J 0
(-2700 4125);
DISPLAY 0.872340 (-2700 4125);
PAINT GREEN (-2700 4125);
DISPLAY INVISIBLE (-2700 4125);
FORCEPROP 2 LAST PATH I263
J 0
(-2425 4275);
DISPLAY 1.021277 (-2425 4275);
DISPLAY INVISIBLE (-2425 4275);
FORCEADD OFFPAGE..3
(-2650 4175);
FORCEPROP 2 LAST $XR0 27 
J 0
(-2436 4175);
DISPLAY 0.638298 (-2436 4175);
PAINT MONO (-2436 4175);
FORCEPROP 2 LAST CDS_LIB standard
J 0
(-2650 4175);
DISPLAY INVISIBLE (-2650 4175);
FORCEPROP 1 LAST OFFPAGE TRUE
J 0
(-2325 4050);
DISPLAY 0.872340 (-2325 4050);
PAINT GREEN (-2325 4050);
DISPLAY INVISIBLE (-2325 4050);
FORCEPROP 1 LAST COMMENT_BODY TRUE
J 0
(-2700 4075);
DISPLAY 0.872340 (-2700 4075);
PAINT GREEN (-2700 4075);
DISPLAY INVISIBLE (-2700 4075);
FORCEPROP 2 LAST PATH I264
J 0
(-2425 4225);
DISPLAY 1.021277 (-2425 4225);
DISPLAY INVISIBLE (-2425 4225);
FORCEADD OFFPAGE..2
(-1400 1475);
FORCEPROP 2 LAST $XR0 164 
J 0
(-1211 1475);
DISPLAY 0.638298 (-1211 1475);
PAINT MONO (-1211 1475);
FORCEPROP 2 LAST CDS_LIB standard
J 0
(-1400 1475);
DISPLAY INVISIBLE (-1400 1475);
FORCEPROP 1 LAST OFFPAGE TRUE
J 0
(-1075 1350);
DISPLAY 0.872340 (-1075 1350);
PAINT GREEN (-1075 1350);
DISPLAY INVISIBLE (-1075 1350);
FORCEPROP 1 LAST COMMENT_BODY TRUE
J 0
(-1445 1380);
DISPLAY 0.872340 (-1445 1380);
PAINT GREEN (-1445 1380);
DISPLAY INVISIBLE (-1445 1380);
FORCEPROP 2 LAST PATH I273
J 0
(-1200 1525);
DISPLAY 1.021277 (-1200 1525);
DISPLAY INVISIBLE (-1200 1525);
FORCEADD OFFPAGE..4
(-1400 1425);
FORCEPROP 2 LAST $XR0 164 
J 0
(-1214 1425);
DISPLAY 0.638298 (-1214 1425);
PAINT MONO (-1214 1425);
FORCEPROP 2 LAST CDS_LIB standard
J 2
(-1400 1425);
DISPLAY INVISIBLE (-1400 1425);
FORCEPROP 1 LAST OFFPAGE TRUE
J 0
(-1075 1300);
DISPLAY 0.872340 (-1075 1300);
PAINT GREEN (-1075 1300);
DISPLAY INVISIBLE (-1075 1300);
FORCEPROP 1 LAST COMMENT_BODY TRUE
J 0
(-1425 1325);
DISPLAY 0.872340 (-1425 1325);
PAINT GREEN (-1425 1325);
DISPLAY INVISIBLE (-1425 1325);
FORCEPROP 2 LAST PATH I274
J 0
(-1200 1475);
DISPLAY 1.021277 (-1200 1475);
DISPLAY INVISIBLE (-1200 1475);
FORCEADD OFFPAGE..4
(-1400 1325);
FORCEPROP 2 LAST $XR0 164 
J 0
(-1214 1325);
DISPLAY 0.638298 (-1214 1325);
PAINT MONO (-1214 1325);
FORCEPROP 2 LAST CDS_LIB standard
J 2
(-1400 1325);
DISPLAY INVISIBLE (-1400 1325);
FORCEPROP 1 LAST OFFPAGE TRUE
J 0
(-1075 1200);
DISPLAY 0.872340 (-1075 1200);
PAINT GREEN (-1075 1200);
DISPLAY INVISIBLE (-1075 1200);
FORCEPROP 1 LAST COMMENT_BODY TRUE
J 0
(-1425 1225);
DISPLAY 0.872340 (-1425 1225);
PAINT GREEN (-1425 1225);
DISPLAY INVISIBLE (-1425 1225);
FORCEPROP 2 LAST PATH I275
J 0
(-1200 1375);
DISPLAY 1.021277 (-1200 1375);
DISPLAY INVISIBLE (-1200 1375);
FORCEADD OFFPAGE..2
(-1400 1375);
FORCEPROP 2 LAST $XR1 164 
J 0
(-1121 1375);
DISPLAY 0.638298 (-1121 1375);
PAINT MONO (-1121 1375);
FORCEPROP 2 LAST $XR0 76 
J 0
(-1211 1375);
DISPLAY 0.638298 (-1211 1375);
PAINT MONO (-1211 1375);
FORCEPROP 2 LAST CDS_LIB standard
J 0
(-1400 1375);
DISPLAY INVISIBLE (-1400 1375);
FORCEPROP 1 LAST OFFPAGE TRUE
J 0
(-1075 1250);
DISPLAY 0.872340 (-1075 1250);
PAINT GREEN (-1075 1250);
DISPLAY INVISIBLE (-1075 1250);
FORCEPROP 1 LAST COMMENT_BODY TRUE
J 0
(-1445 1280);
DISPLAY 0.872340 (-1445 1280);
PAINT GREEN (-1445 1280);
DISPLAY INVISIBLE (-1445 1280);
FORCEPROP 2 LAST PATH I276
J 0
(-1075 1425);
DISPLAY 1.021277 (-1075 1425);
DISPLAY INVISIBLE (-1075 1425);
FORCEADD OFFPAGE..3
(-2650 4125);
FORCEPROP 2 LAST $XR0 27 
J 0
(-2436 4125);
DISPLAY 0.638298 (-2436 4125);
PAINT MONO (-2436 4125);
FORCEPROP 2 LAST CDS_LIB standard
J 0
(-2650 4125);
DISPLAY INVISIBLE (-2650 4125);
FORCEPROP 1 LAST OFFPAGE TRUE
J 0
(-2325 4000);
DISPLAY 0.872340 (-2325 4000);
PAINT GREEN (-2325 4000);
DISPLAY INVISIBLE (-2325 4000);
FORCEPROP 1 LAST COMMENT_BODY TRUE
J 0
(-2700 4025);
DISPLAY 0.872340 (-2700 4025);
PAINT GREEN (-2700 4025);
DISPLAY INVISIBLE (-2700 4025);
FORCEPROP 2 LAST PATH I277
J 0
(-2425 4175);
DISPLAY 1.021277 (-2425 4175);
DISPLAY INVISIBLE (-2425 4175);
FORCEADD OFFPAGE..3
(-2650 4075);
FORCEPROP 2 LAST $XR0 27 
J 0
(-2436 4075);
DISPLAY 0.638298 (-2436 4075);
PAINT MONO (-2436 4075);
FORCEPROP 2 LAST CDS_LIB standard
J 0
(-2650 4075);
DISPLAY INVISIBLE (-2650 4075);
FORCEPROP 1 LAST OFFPAGE TRUE
J 0
(-2325 3950);
DISPLAY 0.872340 (-2325 3950);
PAINT GREEN (-2325 3950);
DISPLAY INVISIBLE (-2325 3950);
FORCEPROP 1 LAST COMMENT_BODY TRUE
J 0
(-2700 3975);
DISPLAY 0.872340 (-2700 3975);
PAINT GREEN (-2700 3975);
DISPLAY INVISIBLE (-2700 3975);
FORCEPROP 2 LAST PATH I278
J 0
(-2425 4125);
DISPLAY 1.021277 (-2425 4125);
DISPLAY INVISIBLE (-2425 4125);
FORCEADD Q_RES..1
R 2
(-2375 1475);
FORCEPROP 1 LAST LOCATION R405
J 2
(-2525 1475);
DISPLAY 0.489362 (-2525 1475);
PAINT SKYBLUE (-2525 1475);
FORCEPROP 0 LAST $SEC 1
J 0
(-2525 1525);
DISPLAY 0.680851 (-2525 1525);
PAINT MONO (-2525 1525);
DISPLAY INVISIBLE (-2525 1525);
FORCEPROP 0 LAST CDS_SEC 1
J 0
(-2525 1525);
DISPLAY 1.021277 (-2525 1525);
DISPLAY INVISIBLE (-2525 1525);
FORCEPROP 1 LASTPIN (-2275 1475) $PN 1
J 2
(-2287 1487);
DISPLAY 0.489362 (-2287 1487);
PAINT MONO (-2287 1487);
FORCEPROP 1 LASTPIN (-2475 1475) $PN 2
J 2
(-2437 1487);
DISPLAY 0.489362 (-2437 1487);
PAINT MONO (-2437 1487);
FORCEPROP 1 LAST VALUE 0
J 0
(-2275 1475);
DISPLAY 0.489362 (-2275 1475);
PAINT SKYBLUE (-2275 1475);
FORCEPROP 2 LAST CDS_LIB pure_quanta
J 0
(-2375 1475);
DISPLAY INVISIBLE (-2375 1475);
FORCEPROP 1 LAST WATTAGE 1/16W
J 0
(-2775 1400);
DISPLAY 0.489362 (-2775 1400);
PAINT SKYBLUE (-2775 1400);
DISPLAY INVISIBLE (-2775 1400);
FORCEPROP 1 LAST MATERIAL CHIP
J 2
(-2800 1400);
DISPLAY 0.489362 (-2800 1400);
PAINT SKYBLUE (-2800 1400);
DISPLAY INVISIBLE (-2800 1400);
FORCEPROP 1 LAST TOLERANCE 5%
J 2
(-2350 1400);
DISPLAY 0.489362 (-2350 1400);
PAINT SKYBLUE (-2350 1400);
DISPLAY INVISIBLE (-2350 1400);
FORCEPROP 1 LAST PACK_TYPE 0402LF
J 2
(-2425 1400);
DISPLAY 0.489362 (-2425 1400);
PAINT SKYBLUE (-2425 1400);
DISPLAY INVISIBLE (-2425 1400);
FORCEPROP 1 LAST PATH I279
J 2
(-2325 1625);
DISPLAY 0.978723 (-2325 1625);
PAINT WHITE (-2325 1625);
DISPLAY INVISIBLE (-2325 1625);
FORCEPROP 1 LAST PART_NUMBER CS00002JB13
J 2
(-2400 1525);
DISPLAY 0.489362 (-2400 1525);
PAINT SKYBLUE (-2400 1525);
DISPLAY INVISIBLE (-2400 1525);
FORCEADD OFFPAGE..2
R 2
(-1250 2175);
FORCEPROP 2 LAST $XR0 27 
J 0
(-1474 2175);
DISPLAY 0.638298 (-1474 2175);
PAINT MONO (-1474 2175);
FORCEPROP 2 LAST CDS_LIB standard
J 0
(-1250 2175);
DISPLAY INVISIBLE (-1250 2175);
FORCEPROP 1 LAST OFFPAGE TRUE
J 2
(-1575 2050);
DISPLAY 0.872340 (-1575 2050);
PAINT GREEN (-1575 2050);
DISPLAY INVISIBLE (-1575 2050);
FORCEPROP 1 LAST COMMENT_BODY TRUE
J 2
(-1205 2080);
DISPLAY 0.872340 (-1205 2080);
PAINT PEACH (-1205 2080);
DISPLAY INVISIBLE (-1205 2080);
FORCEPROP 2 LAST PATH I283
J 0
(-1200 2250);
DISPLAY 1.021277 (-1200 2250);
DISPLAY INVISIBLE (-1200 2250);
FORCEADD OFFPAGE..2
R 2
(-1250 2225);
FORCEPROP 2 LAST $XR0 27 
J 0
(-1474 2225);
DISPLAY 0.638298 (-1474 2225);
PAINT MONO (-1474 2225);
FORCEPROP 2 LAST CDS_LIB standard
J 0
(-1250 2225);
DISPLAY INVISIBLE (-1250 2225);
FORCEPROP 1 LAST OFFPAGE TRUE
J 2
(-1575 2100);
DISPLAY 0.872340 (-1575 2100);
PAINT GREEN (-1575 2100);
DISPLAY INVISIBLE (-1575 2100);
FORCEPROP 1 LAST COMMENT_BODY TRUE
J 2
(-1205 2130);
DISPLAY 0.872340 (-1205 2130);
PAINT PEACH (-1205 2130);
DISPLAY INVISIBLE (-1205 2130);
FORCEPROP 2 LAST PATH I284
J 0
(-1200 2300);
DISPLAY 1.021277 (-1200 2300);
DISPLAY INVISIBLE (-1200 2300);
FORCEADD OFFPAGE..2
R 2
(-1250 2275);
FORCEPROP 2 LAST $XR0 27 
J 0
(-1474 2275);
DISPLAY 0.638298 (-1474 2275);
PAINT MONO (-1474 2275);
FORCEPROP 2 LAST CDS_LIB standard
J 0
(-1250 2275);
DISPLAY INVISIBLE (-1250 2275);
FORCEPROP 1 LAST OFFPAGE TRUE
J 2
(-1575 2150);
DISPLAY 0.872340 (-1575 2150);
PAINT GREEN (-1575 2150);
DISPLAY INVISIBLE (-1575 2150);
FORCEPROP 1 LAST COMMENT_BODY TRUE
J 2
(-1205 2180);
DISPLAY 0.872340 (-1205 2180);
PAINT PEACH (-1205 2180);
DISPLAY INVISIBLE (-1205 2180);
FORCEPROP 2 LAST PATH I285
J 0
(-1200 2350);
DISPLAY 1.021277 (-1200 2350);
DISPLAY INVISIBLE (-1200 2350);
FORCEADD OFFPAGE..2
R 2
(-1250 2325);
FORCEPROP 2 LAST $XR0 27 
J 0
(-1474 2325);
DISPLAY 0.638298 (-1474 2325);
PAINT MONO (-1474 2325);
FORCEPROP 2 LAST CDS_LIB standard
J 0
(-1250 2325);
DISPLAY INVISIBLE (-1250 2325);
FORCEPROP 1 LAST OFFPAGE TRUE
J 2
(-1575 2200);
DISPLAY 0.872340 (-1575 2200);
PAINT GREEN (-1575 2200);
DISPLAY INVISIBLE (-1575 2200);
FORCEPROP 1 LAST COMMENT_BODY TRUE
J 2
(-1205 2230);
DISPLAY 0.872340 (-1205 2230);
PAINT PEACH (-1205 2230);
DISPLAY INVISIBLE (-1205 2230);
FORCEPROP 2 LAST PATH I286
J 0
(-1200 2400);
DISPLAY 1.021277 (-1200 2400);
DISPLAY INVISIBLE (-1200 2400);
FORCEADD Q_RES..1
(-2375 1375);
FORCEPROP 1 LAST LOCATION R2318
J 0
(-2575 1375);
DISPLAY 0.489362 (-2575 1375);
PAINT SKYBLUE (-2575 1375);
FORCEPROP 0 LAST $SEC 1
J 0
(-2225 1400);
DISPLAY 0.680851 (-2225 1400);
PAINT MONO (-2225 1400);
DISPLAY INVISIBLE (-2225 1400);
FORCEPROP 0 LAST CDS_SEC 1
J 0
(-2225 1400);
DISPLAY 1.021277 (-2225 1400);
DISPLAY INVISIBLE (-2225 1400);
FORCEPROP 1 LASTPIN (-2475 1375) $PN 1
J 0
(-2463 1387);
DISPLAY 0.489362 (-2463 1387);
PAINT MONO (-2463 1387);
FORCEPROP 1 LASTPIN (-2275 1375) $PN 2
J 0
(-2313 1387);
DISPLAY 0.489362 (-2313 1387);
PAINT MONO (-2313 1387);
FORCEPROP 1 LAST VALUE 0
J 2
(-2225 1375);
DISPLAY 0.489362 (-2225 1375);
PAINT SKYBLUE (-2225 1375);
FORCEPROP 2 LAST CDS_LIB pure_quanta
J 0
(-2375 1375);
DISPLAY INVISIBLE (-2375 1375);
FORCEPROP 1 LAST WATTAGE 1/16W
J 2
(-1975 1300);
DISPLAY 0.489362 (-1975 1300);
PAINT SKYBLUE (-1975 1300);
DISPLAY INVISIBLE (-1975 1300);
FORCEPROP 1 LAST MATERIAL CHIP
J 0
(-1950 1300);
DISPLAY 0.489362 (-1950 1300);
PAINT SKYBLUE (-1950 1300);
DISPLAY INVISIBLE (-1950 1300);
FORCEPROP 1 LAST TOLERANCE 5%
J 0
(-2400 1300);
DISPLAY 0.489362 (-2400 1300);
PAINT SKYBLUE (-2400 1300);
DISPLAY INVISIBLE (-2400 1300);
FORCEPROP 1 LAST PACK_TYPE 0402LF
J 0
(-2325 1300);
DISPLAY 0.489362 (-2325 1300);
PAINT SKYBLUE (-2325 1300);
DISPLAY INVISIBLE (-2325 1300);
FORCEPROP 1 LAST PATH I288
J 0
(-2425 1525);
DISPLAY 0.978723 (-2425 1525);
PAINT WHITE (-2425 1525);
DISPLAY INVISIBLE (-2425 1525);
FORCEPROP 1 LAST PART_NUMBER CS00002JB13
J 0
(-2350 1425);
DISPLAY 0.489362 (-2350 1425);
PAINT SKYBLUE (-2350 1425);
DISPLAY INVISIBLE (-2350 1425);
FORCEADD UNIVERSAL_POWER..1
(-8000 1575);
FORCEPROP 3 LASTPIN (-8000 1525) SIG_NAME PVDD18_S5_P0\g
J 0
(-7990 1535);
DISPLAY 0.659574 (-7990 1535);
PAINT MONO (-7990 1535);
DISPLAY INVISIBLE (-7990 1535);
FORCEPROP 1 LAST HDL_POWER PVDD18_S5_P0
J 1
(-8000 1625);
DISPLAY 0.489362 (-8000 1625);
PAINT GREEN (-8000 1625);
FORCEPROP 2 LAST CDS_LIB pure_quanta_power
J 0
(-8000 1575);
DISPLAY INVISIBLE (-8000 1575);
FORCEPROP 1 LAST PATH I293
J 0
(-7950 1600);
DISPLAY 0.872340 (-7950 1600);
PAINT AQUA (-7950 1600);
DISPLAY INVISIBLE (-7950 1600);
FORCEADD Q_RES..2
(-6375 1300);
FORCEPROP 1 LAST LOCATION R403
J 0
(-6350 1400);
DISPLAY 0.489362 (-6350 1400);
PAINT SKYBLUE (-6350 1400);
FORCEPROP 0 LAST $SEC 1
J 0
(-6350 1450);
DISPLAY 0.680851 (-6350 1450);
PAINT MONO (-6350 1450);
DISPLAY INVISIBLE (-6350 1450);
FORCEPROP 0 LAST CDS_SEC 1
J 0
(-6350 1450);
DISPLAY 1.021277 (-6350 1450);
DISPLAY INVISIBLE (-6350 1450);
FORCEPROP 1 LASTPIN (-6375 1400) $PN 1
J 0
(-6370 1362);
DISPLAY 0.489362 (-6370 1362);
PAINT MONO (-6370 1362);
FORCEPROP 1 LASTPIN (-6375 1200) $PN 2
J 0
(-6370 1210);
DISPLAY 0.489362 (-6370 1210);
PAINT MONO (-6370 1210);
FORCEPROP 1 LAST TOLERANCE 1%
J 0
(-6350 1300);
DISPLAY 0.489362 (-6350 1300);
PAINT SKYBLUE (-6350 1300);
FORCEPROP 1 LAST VALUE 1K
J 0
(-6350 1350);
DISPLAY 0.489362 (-6350 1350);
PAINT SKYBLUE (-6350 1350);
FORCEPROP 1 LAST WATTAGE 1/16W
J 0
(-6350 1250);
DISPLAY 0.489362 (-6350 1250);
PAINT SKYBLUE (-6350 1250);
FORCEPROP 1 LAST MATERIAL CHIP
J 0
(-6350 1200);
DISPLAY 0.489362 (-6350 1200);
PAINT SKYBLUE (-6350 1200);
FORCEPROP 1 LAST PACK_TYPE 0402LF
J 0
(-6350 1150);
DISPLAY 0.489362 (-6350 1150);
PAINT SKYBLUE (-6350 1150);
FORCEPROP 2 LAST CDS_LIB pure_quanta
J 0
(-6375 1300);
DISPLAY INVISIBLE (-6375 1300);
FORCEPROP 1 LAST PATH I294
J 0
(-6325 1475);
DISPLAY 0.978723 (-6325 1475);
PAINT WHITE (-6325 1475);
DISPLAY INVISIBLE (-6325 1475);
FORCEPROP 1 LAST PART_NUMBER CS21002FB06
J 0
(-6350 1100);
DISPLAY 0.489362 (-6350 1100);
PAINT SKYBLUE (-6350 1100);
DISPLAY INVISIBLE (-6350 1100);
FORCEADD Q_CAP..1
(-6375 600);
FORCEPROP 1 LAST LOCATION C212
J 0
(-6325 700);
DISPLAY 0.489362 (-6325 700);
PAINT SKYBLUE (-6325 700);
FORCEPROP 0 LAST $SEC 1
J 0
(-6325 750);
DISPLAY 0.680851 (-6325 750);
PAINT MONO (-6325 750);
DISPLAY INVISIBLE (-6325 750);
FORCEPROP 0 LAST CDS_SEC 1
J 0
(-6325 750);
DISPLAY 1.021277 (-6325 750);
DISPLAY INVISIBLE (-6325 750);
FORCEPROP 1 LASTPIN (-6375 700) $PN 1
J 0
(-6365 680);
DISPLAY 0.489362 (-6365 680);
PAINT MONO (-6365 680);
FORCEPROP 1 LASTPIN (-6375 500) $PN 2
J 0
(-6365 480);
DISPLAY 0.489362 (-6365 480);
PAINT MONO (-6365 480);
FORCEPROP 1 LAST VOLTAGE 50V
J 0
(-6325 600);
DISPLAY 0.489362 (-6325 600);
PAINT SKYBLUE (-6325 600);
FORCEPROP 1 LAST VALUE 0.001UF
J 0
(-6325 650);
DISPLAY 0.489362 (-6325 650);
PAINT SKYBLUE (-6325 650);
FORCEPROP 1 LAST PACK_TYPE C0402
J 0
(-6325 450);
DISPLAY 0.489362 (-6325 450);
PAINT SKYBLUE (-6325 450);
FORCEPROP 1 LAST TOLERANCE 10%
J 0
(-6325 550);
DISPLAY 0.489362 (-6325 550);
PAINT SKYBLUE (-6325 550);
FORCEPROP 1 LAST MATERIAL EMPTY
J 0
(-6325 400);
DISPLAY 0.489362 (-6325 400);
PAINT RED (-6325 400);
FORCEPROP 2 LAST CDS_LIB pure_quanta
J 0
(-6375 600);
DISPLAY INVISIBLE (-6375 600);
FORCEPROP 1 LAST PATH I295
J 0
(-6325 750);
DISPLAY 0.978723 (-6325 750);
PAINT WHITE (-6325 750);
DISPLAY INVISIBLE (-6325 750);
FORCEPROP 1 LAST PART_NUMBER CH30106KB19
J 0
(-6325 500);
DISPLAY 0.489362 (-6325 500);
PAINT SKYBLUE (-6325 500);
DISPLAY INVISIBLE (-6325 500);
FORCEADD Q_RES..2
(-6675 1300);
FORCEPROP 1 LAST LOCATION R402
J 0
(-6650 1400);
DISPLAY 0.489362 (-6650 1400);
PAINT SKYBLUE (-6650 1400);
FORCEPROP 2 LAST $SEC 1
J 0
(-6625 1525);
DISPLAY 0.680851 (-6625 1525);
PAINT MONO (-6625 1525);
DISPLAY INVISIBLE (-6625 1525);
FORCEPROP 2 LAST CDS_SEC 1
J 0
(-6625 1525);
DISPLAY 1.021277 (-6625 1525);
DISPLAY INVISIBLE (-6625 1525);
FORCEPROP 1 LASTPIN (-6675 1400) $PN 1
J 0
(-6670 1362);
DISPLAY 0.489362 (-6670 1362);
FORCEPROP 1 LASTPIN (-6675 1200) $PN 2
J 0
(-6670 1210);
DISPLAY 0.489362 (-6670 1210);
FORCEPROP 1 LAST TOLERANCE 1%
J 0
(-6650 1300);
DISPLAY 0.489362 (-6650 1300);
PAINT SKYBLUE (-6650 1300);
FORCEPROP 1 LAST WATTAGE 1/16W
J 0
(-6650 1250);
DISPLAY 0.489362 (-6650 1250);
PAINT SKYBLUE (-6650 1250);
FORCEPROP 1 LAST VALUE 1K
J 0
(-6650 1350);
DISPLAY 0.489362 (-6650 1350);
PAINT SKYBLUE (-6650 1350);
FORCEPROP 1 LAST MATERIAL CHIP
J 0
(-6650 1200);
DISPLAY 0.489362 (-6650 1200);
PAINT SKYBLUE (-6650 1200);
FORCEPROP 1 LAST PACK_TYPE 0402LF
J 0
(-6650 1150);
DISPLAY 0.489362 (-6650 1150);
PAINT SKYBLUE (-6650 1150);
FORCEPROP 2 LAST CDS_LIB pure_quanta
J 0
(-6675 1300);
DISPLAY INVISIBLE (-6675 1300);
FORCEPROP 1 LAST PATH I296
J 0
(-6625 1475);
DISPLAY 0.978723 (-6625 1475);
PAINT WHITE (-6625 1475);
DISPLAY INVISIBLE (-6625 1475);
FORCEPROP 1 LAST PART_NUMBER CS21002FB06
J 0
(-6635 1175);
DISPLAY 0.617021 (-6635 1175);
PAINT SKYBLUE (-6635 1175);
DISPLAY INVISIBLE (-6635 1175);
FORCEADD Q_CAP..1
(-6675 600);
FORCEPROP 1 LAST LOCATION C211
J 0
(-6625 700);
DISPLAY 0.489362 (-6625 700);
PAINT SKYBLUE (-6625 700);
FORCEPROP 0 LAST $SEC 1
J 0
(-6625 750);
PAINT MONO (-6625 750);
DISPLAY INVISIBLE (-6625 750);
FORCEPROP 0 LAST CDS_SEC 1
J 0
(-6625 750);
PAINT MONO (-6625 750);
DISPLAY INVISIBLE (-6625 750);
FORCEPROP 1 LASTPIN (-6675 700) $PN 1
J 0
(-6665 680);
DISPLAY 0.489362 (-6665 680);
PAINT GREEN (-6665 680);
FORCEPROP 1 LASTPIN (-6675 500) $PN 2
J 0
(-6665 480);
DISPLAY 0.489362 (-6665 480);
PAINT GREEN (-6665 480);
FORCEPROP 1 LAST VOLTAGE 50V
J 0
(-6625 600);
DISPLAY 0.489362 (-6625 600);
PAINT SKYBLUE (-6625 600);
FORCEPROP 1 LAST PACK_TYPE C0402
J 0
(-6625 450);
DISPLAY 0.489362 (-6625 450);
PAINT SKYBLUE (-6625 450);
FORCEPROP 1 LAST VALUE 0.001UF
J 0
(-6625 650);
DISPLAY 0.489362 (-6625 650);
PAINT SKYBLUE (-6625 650);
FORCEPROP 1 LAST TOLERANCE 10%
J 0
(-6625 550);
DISPLAY 0.489362 (-6625 550);
PAINT SKYBLUE (-6625 550);
FORCEPROP 1 LAST MATERIAL EMPTY
J 0
(-6625 400);
DISPLAY 0.489362 (-6625 400);
PAINT RED (-6625 400);
FORCEPROP 2 LAST CDS_LIB pure_quanta
J 0
(-6675 600);
PAINT MONO (-6675 600);
DISPLAY INVISIBLE (-6675 600);
FORCEPROP 1 LAST PATH I297
J 0
(-6625 750);
DISPLAY 0.978723 (-6625 750);
PAINT WHITE (-6625 750);
DISPLAY INVISIBLE (-6625 750);
FORCEPROP 1 LAST PART_NUMBER CH30106KB19
J 0
(-6625 500);
DISPLAY 0.808511 (-6625 500);
PAINT SKYBLUE (-6625 500);
DISPLAY INVISIBLE (-6625 500);
FORCEADD GND..1
(-6375 300);
FORCEPROP 3 LASTPIN (-6375 350) SIG_NAME GND\g
J 0
(-6365 360);
DISPLAY 0.659574 (-6365 360);
PAINT MONO (-6365 360);
DISPLAY INVISIBLE (-6365 360);
FORCEPROP 2 LAST CDS_LIB pure_quanta_power
J 0
(-6375 300);
DISPLAY INVISIBLE (-6375 300);
FORCEPROP 1 LAST SIZE 1B
J 0
(-6300 250);
DISPLAY 0.872340 (-6300 250);
PAINT GREEN (-6300 250);
DISPLAY INVISIBLE (-6300 250);
FORCEPROP 1 LAST HDL_POWER GND
J 0
(-6375 450);
DISPLAY 0.872340 (-6375 450);
PAINT GREEN (-6375 450);
DISPLAY INVISIBLE (-6375 450);
FORCEPROP 1 LAST PATH I298
J 0
(-6300 300);
DISPLAY 0.872340 (-6300 300);
PAINT AQUA (-6300 300);
DISPLAY INVISIBLE (-6300 300);
FORCEADD GND..1
(-6675 300);
FORCEPROP 3 LASTPIN (-6675 350) SIG_NAME GND\g
J 0
(-6665 360);
DISPLAY 0.659574 (-6665 360);
PAINT MONO (-6665 360);
DISPLAY INVISIBLE (-6665 360);
FORCEPROP 2 LAST CDS_LIB pure_quanta_power
J 0
(-6675 300);
DISPLAY INVISIBLE (-6675 300);
FORCEPROP 1 LAST SIZE 1B
J 0
(-6600 250);
DISPLAY 0.872340 (-6600 250);
PAINT GREEN (-6600 250);
DISPLAY INVISIBLE (-6600 250);
FORCEPROP 1 LAST HDL_POWER GND
J 0
(-6675 450);
DISPLAY 0.872340 (-6675 450);
PAINT GREEN (-6675 450);
DISPLAY INVISIBLE (-6675 450);
FORCEPROP 1 LAST PATH I299
J 0
(-6600 300);
DISPLAY 0.872340 (-6600 300);
PAINT AQUA (-6600 300);
DISPLAY INVISIBLE (-6600 300);
FORCEADD Q_RES..2
(-7025 1300);
FORCEPROP 1 LAST LOCATION R401
J 0
(-7000 1400);
DISPLAY 0.489362 (-7000 1400);
PAINT SKYBLUE (-7000 1400);
FORCEPROP 2 LAST $SEC 1
J 0
(-6975 1525);
DISPLAY 0.680851 (-6975 1525);
PAINT MONO (-6975 1525);
DISPLAY INVISIBLE (-6975 1525);
FORCEPROP 2 LAST CDS_SEC 1
J 0
(-6975 1525);
DISPLAY 1.021277 (-6975 1525);
DISPLAY INVISIBLE (-6975 1525);
FORCEPROP 1 LASTPIN (-7025 1400) $PN 1
J 0
(-7020 1362);
DISPLAY 0.489362 (-7020 1362);
FORCEPROP 1 LASTPIN (-7025 1200) $PN 2
J 0
(-7020 1210);
DISPLAY 0.489362 (-7020 1210);
FORCEPROP 1 LAST TOLERANCE 1%
J 0
(-7000 1300);
DISPLAY 0.489362 (-7000 1300);
PAINT SKYBLUE (-7000 1300);
FORCEPROP 1 LAST VALUE 1K
J 0
(-7000 1350);
DISPLAY 0.489362 (-7000 1350);
PAINT SKYBLUE (-7000 1350);
FORCEPROP 1 LAST MATERIAL CHIP
J 0
(-7000 1200);
DISPLAY 0.489362 (-7000 1200);
PAINT SKYBLUE (-7000 1200);
FORCEPROP 1 LAST PACK_TYPE 0402LF
J 0
(-7000 1150);
DISPLAY 0.489362 (-7000 1150);
PAINT SKYBLUE (-7000 1150);
FORCEPROP 1 LAST WATTAGE 1/16W
J 0
(-7000 1250);
DISPLAY 0.489362 (-7000 1250);
PAINT SKYBLUE (-7000 1250);
FORCEPROP 2 LAST CDS_LIB pure_quanta
J 0
(-7025 1300);
DISPLAY INVISIBLE (-7025 1300);
FORCEPROP 1 LAST PATH I300
J 0
(-6975 1475);
DISPLAY 0.978723 (-6975 1475);
PAINT WHITE (-6975 1475);
DISPLAY INVISIBLE (-6975 1475);
FORCEPROP 1 LAST PART_NUMBER CS21002FB06
J 0
(-6985 1175);
DISPLAY 0.617021 (-6985 1175);
PAINT SKYBLUE (-6985 1175);
DISPLAY INVISIBLE (-6985 1175);
FORCEADD Q_RES..2
(-7350 1300);
FORCEPROP 1 LAST LOCATION R400
J 0
(-7325 1400);
DISPLAY 0.489362 (-7325 1400);
PAINT SKYBLUE (-7325 1400);
FORCEPROP 2 LAST $SEC 1
J 0
(-7300 1525);
DISPLAY 0.680851 (-7300 1525);
PAINT MONO (-7300 1525);
DISPLAY INVISIBLE (-7300 1525);
FORCEPROP 2 LAST CDS_SEC 1
J 0
(-7300 1525);
DISPLAY 1.021277 (-7300 1525);
DISPLAY INVISIBLE (-7300 1525);
FORCEPROP 1 LASTPIN (-7350 1400) $PN 1
J 0
(-7345 1362);
DISPLAY 0.489362 (-7345 1362);
FORCEPROP 1 LASTPIN (-7350 1200) $PN 2
J 0
(-7345 1210);
DISPLAY 0.489362 (-7345 1210);
FORCEPROP 1 LAST TOLERANCE 1%
J 0
(-7325 1300);
DISPLAY 0.489362 (-7325 1300);
PAINT SKYBLUE (-7325 1300);
FORCEPROP 1 LAST WATTAGE 1/16W
J 0
(-7325 1250);
DISPLAY 0.489362 (-7325 1250);
PAINT SKYBLUE (-7325 1250);
FORCEPROP 1 LAST MATERIAL CHIP
J 0
(-7325 1200);
DISPLAY 0.489362 (-7325 1200);
PAINT SKYBLUE (-7325 1200);
FORCEPROP 1 LAST VALUE 1K
J 0
(-7325 1350);
DISPLAY 0.489362 (-7325 1350);
PAINT SKYBLUE (-7325 1350);
FORCEPROP 1 LAST PACK_TYPE 0402LF
J 0
(-7325 1150);
DISPLAY 0.489362 (-7325 1150);
PAINT SKYBLUE (-7325 1150);
FORCEPROP 2 LAST CDS_LIB pure_quanta
J 0
(-7350 1300);
DISPLAY INVISIBLE (-7350 1300);
FORCEPROP 1 LAST PATH I301
J 0
(-7300 1475);
DISPLAY 0.978723 (-7300 1475);
PAINT WHITE (-7300 1475);
DISPLAY INVISIBLE (-7300 1475);
FORCEPROP 1 LAST PART_NUMBER CS21002FB06
J 0
(-7310 1175);
DISPLAY 0.617021 (-7310 1175);
PAINT SKYBLUE (-7310 1175);
DISPLAY INVISIBLE (-7310 1175);
FORCEADD Q_CAP..1
(-7025 600);
FORCEPROP 1 LAST LOCATION C210
J 0
(-6975 700);
DISPLAY 0.489362 (-6975 700);
PAINT SKYBLUE (-6975 700);
FORCEPROP 0 LAST $SEC 1
J 0
(-6975 750);
PAINT MONO (-6975 750);
DISPLAY INVISIBLE (-6975 750);
FORCEPROP 0 LAST CDS_SEC 1
J 0
(-6975 750);
PAINT MONO (-6975 750);
DISPLAY INVISIBLE (-6975 750);
FORCEPROP 1 LASTPIN (-7025 700) $PN 1
J 0
(-7015 680);
DISPLAY 0.489362 (-7015 680);
PAINT GREEN (-7015 680);
FORCEPROP 1 LASTPIN (-7025 500) $PN 2
J 0
(-7015 480);
DISPLAY 0.489362 (-7015 480);
PAINT GREEN (-7015 480);
FORCEPROP 1 LAST PACK_TYPE C0402
J 0
(-6975 450);
DISPLAY 0.489362 (-6975 450);
PAINT SKYBLUE (-6975 450);
FORCEPROP 1 LAST VOLTAGE 50V
J 0
(-6975 600);
DISPLAY 0.489362 (-6975 600);
PAINT SKYBLUE (-6975 600);
FORCEPROP 1 LAST VALUE 0.001UF
J 0
(-6975 650);
DISPLAY 0.489362 (-6975 650);
PAINT SKYBLUE (-6975 650);
FORCEPROP 1 LAST TOLERANCE 10%
J 0
(-6975 550);
DISPLAY 0.489362 (-6975 550);
PAINT SKYBLUE (-6975 550);
FORCEPROP 1 LAST MATERIAL EMPTY
J 0
(-6975 400);
DISPLAY 0.489362 (-6975 400);
PAINT RED (-6975 400);
FORCEPROP 2 LAST CDS_LIB pure_quanta
J 0
(-7025 600);
PAINT MONO (-7025 600);
DISPLAY INVISIBLE (-7025 600);
FORCEPROP 1 LAST PATH I302
J 0
(-6975 750);
DISPLAY 0.978723 (-6975 750);
PAINT WHITE (-6975 750);
DISPLAY INVISIBLE (-6975 750);
FORCEPROP 1 LAST PART_NUMBER CH30106KB19
J 0
(-6975 500);
DISPLAY 0.808511 (-6975 500);
PAINT SKYBLUE (-6975 500);
DISPLAY INVISIBLE (-6975 500);
FORCEADD Q_CAP..1
(-7350 600);
FORCEPROP 1 LAST LOCATION C209
J 0
(-7300 700);
DISPLAY 0.489362 (-7300 700);
PAINT SKYBLUE (-7300 700);
FORCEPROP 0 LAST $SEC 1
J 0
(-7300 750);
PAINT MONO (-7300 750);
DISPLAY INVISIBLE (-7300 750);
FORCEPROP 0 LAST CDS_SEC 1
J 0
(-7300 750);
PAINT MONO (-7300 750);
DISPLAY INVISIBLE (-7300 750);
FORCEPROP 1 LASTPIN (-7350 700) $PN 1
J 0
(-7340 680);
DISPLAY 0.489362 (-7340 680);
PAINT GREEN (-7340 680);
FORCEPROP 1 LASTPIN (-7350 500) $PN 2
J 0
(-7340 480);
DISPLAY 0.489362 (-7340 480);
PAINT GREEN (-7340 480);
FORCEPROP 1 LAST PACK_TYPE C0402
J 0
(-7300 450);
DISPLAY 0.489362 (-7300 450);
PAINT SKYBLUE (-7300 450);
FORCEPROP 1 LAST VOLTAGE 50V
J 0
(-7300 600);
DISPLAY 0.489362 (-7300 600);
PAINT SKYBLUE (-7300 600);
FORCEPROP 1 LAST VALUE 0.001UF
J 0
(-7300 650);
DISPLAY 0.489362 (-7300 650);
PAINT SKYBLUE (-7300 650);
FORCEPROP 1 LAST TOLERANCE 10%
J 0
(-7300 550);
DISPLAY 0.489362 (-7300 550);
PAINT SKYBLUE (-7300 550);
FORCEPROP 1 LAST MATERIAL EMPTY
J 0
(-7300 400);
DISPLAY 0.489362 (-7300 400);
PAINT RED (-7300 400);
FORCEPROP 2 LAST CDS_LIB pure_quanta
J 0
(-7350 600);
PAINT MONO (-7350 600);
DISPLAY INVISIBLE (-7350 600);
FORCEPROP 1 LAST PATH I303
J 0
(-7300 750);
DISPLAY 0.978723 (-7300 750);
PAINT WHITE (-7300 750);
DISPLAY INVISIBLE (-7300 750);
FORCEPROP 1 LAST PART_NUMBER CH30106KB19
J 0
(-7300 500);
DISPLAY 0.808511 (-7300 500);
PAINT SKYBLUE (-7300 500);
DISPLAY INVISIBLE (-7300 500);
FORCEADD Q_RES..2
(-7675 1300);
FORCEPROP 1 LAST LOCATION R399
J 0
(-7650 1400);
DISPLAY 0.489362 (-7650 1400);
PAINT SKYBLUE (-7650 1400);
FORCEPROP 2 LAST $SEC 1
J 0
(-7625 1525);
DISPLAY 0.680851 (-7625 1525);
PAINT MONO (-7625 1525);
DISPLAY INVISIBLE (-7625 1525);
FORCEPROP 2 LAST CDS_SEC 1
J 0
(-7625 1525);
DISPLAY 1.021277 (-7625 1525);
DISPLAY INVISIBLE (-7625 1525);
FORCEPROP 1 LASTPIN (-7675 1400) $PN 1
J 0
(-7670 1362);
DISPLAY 0.489362 (-7670 1362);
FORCEPROP 1 LASTPIN (-7675 1200) $PN 2
J 0
(-7670 1210);
DISPLAY 0.489362 (-7670 1210);
FORCEPROP 1 LAST TOLERANCE 1%
J 0
(-7650 1300);
DISPLAY 0.489362 (-7650 1300);
PAINT SKYBLUE (-7650 1300);
FORCEPROP 1 LAST WATTAGE 1/16W
J 0
(-7650 1250);
DISPLAY 0.489362 (-7650 1250);
PAINT SKYBLUE (-7650 1250);
FORCEPROP 1 LAST MATERIAL CHIP
J 0
(-7650 1200);
DISPLAY 0.489362 (-7650 1200);
PAINT SKYBLUE (-7650 1200);
FORCEPROP 1 LAST VALUE 1K
J 0
(-7650 1350);
DISPLAY 0.489362 (-7650 1350);
PAINT SKYBLUE (-7650 1350);
FORCEPROP 1 LAST PACK_TYPE 0402LF
J 0
(-7650 1150);
DISPLAY 0.489362 (-7650 1150);
PAINT SKYBLUE (-7650 1150);
FORCEPROP 2 LAST CDS_LIB pure_quanta
J 0
(-7675 1300);
DISPLAY INVISIBLE (-7675 1300);
FORCEPROP 1 LAST PATH I304
J 0
(-7625 1475);
DISPLAY 0.978723 (-7625 1475);
PAINT WHITE (-7625 1475);
DISPLAY INVISIBLE (-7625 1475);
FORCEPROP 1 LAST PART_NUMBER CS21002FB06
J 0
(-7635 1175);
DISPLAY 0.617021 (-7635 1175);
PAINT SKYBLUE (-7635 1175);
DISPLAY INVISIBLE (-7635 1175);
FORCEADD Q_RES..2
(-8000 1300);
FORCEPROP 1 LAST LOCATION R398
J 0
(-7975 1400);
DISPLAY 0.489362 (-7975 1400);
PAINT SKYBLUE (-7975 1400);
FORCEPROP 2 LAST $SEC 1
J 0
(-7950 1525);
DISPLAY 0.680851 (-7950 1525);
PAINT MONO (-7950 1525);
DISPLAY INVISIBLE (-7950 1525);
FORCEPROP 2 LAST CDS_SEC 1
J 0
(-7950 1525);
DISPLAY 1.021277 (-7950 1525);
DISPLAY INVISIBLE (-7950 1525);
FORCEPROP 1 LASTPIN (-8000 1400) $PN 1
J 0
(-7995 1362);
DISPLAY 0.489362 (-7995 1362);
FORCEPROP 1 LASTPIN (-8000 1200) $PN 2
J 0
(-7995 1210);
DISPLAY 0.489362 (-7995 1210);
FORCEPROP 1 LAST TOLERANCE 1%
J 0
(-7975 1300);
DISPLAY 0.489362 (-7975 1300);
PAINT SKYBLUE (-7975 1300);
FORCEPROP 1 LAST WATTAGE 1/16W
J 0
(-7975 1250);
DISPLAY 0.489362 (-7975 1250);
PAINT SKYBLUE (-7975 1250);
FORCEPROP 1 LAST MATERIAL CHIP
J 0
(-7975 1200);
DISPLAY 0.489362 (-7975 1200);
PAINT SKYBLUE (-7975 1200);
FORCEPROP 1 LAST VALUE 1K
J 0
(-7975 1350);
DISPLAY 0.489362 (-7975 1350);
PAINT SKYBLUE (-7975 1350);
FORCEPROP 1 LAST PACK_TYPE 0402LF
J 0
(-7975 1150);
DISPLAY 0.489362 (-7975 1150);
PAINT SKYBLUE (-7975 1150);
FORCEPROP 2 LAST CDS_LIB pure_quanta
J 0
(-8000 1300);
DISPLAY INVISIBLE (-8000 1300);
FORCEPROP 1 LAST PATH I305
J 0
(-7950 1475);
DISPLAY 0.978723 (-7950 1475);
PAINT WHITE (-7950 1475);
DISPLAY INVISIBLE (-7950 1475);
FORCEPROP 1 LAST PART_NUMBER CS21002FB06
J 0
(-7960 1175);
DISPLAY 0.617021 (-7960 1175);
PAINT SKYBLUE (-7960 1175);
DISPLAY INVISIBLE (-7960 1175);
FORCEADD Q_CAP..1
(-7675 600);
FORCEPROP 1 LAST LOCATION C208
J 0
(-7625 700);
DISPLAY 0.489362 (-7625 700);
PAINT SKYBLUE (-7625 700);
FORCEPROP 0 LAST $SEC 1
J 0
(-7625 750);
PAINT MONO (-7625 750);
DISPLAY INVISIBLE (-7625 750);
FORCEPROP 0 LAST CDS_SEC 1
J 0
(-7625 750);
PAINT MONO (-7625 750);
DISPLAY INVISIBLE (-7625 750);
FORCEPROP 1 LASTPIN (-7675 700) $PN 1
J 0
(-7665 680);
DISPLAY 0.489362 (-7665 680);
PAINT GREEN (-7665 680);
FORCEPROP 1 LASTPIN (-7675 500) $PN 2
J 0
(-7665 480);
DISPLAY 0.489362 (-7665 480);
PAINT GREEN (-7665 480);
FORCEPROP 1 LAST PACK_TYPE C0402
J 0
(-7625 450);
DISPLAY 0.489362 (-7625 450);
PAINT SKYBLUE (-7625 450);
FORCEPROP 1 LAST VOLTAGE 50V
J 0
(-7625 600);
DISPLAY 0.489362 (-7625 600);
PAINT SKYBLUE (-7625 600);
FORCEPROP 1 LAST VALUE 0.001UF
J 0
(-7625 650);
DISPLAY 0.489362 (-7625 650);
PAINT SKYBLUE (-7625 650);
FORCEPROP 1 LAST TOLERANCE 10%
J 0
(-7625 550);
DISPLAY 0.489362 (-7625 550);
PAINT SKYBLUE (-7625 550);
FORCEPROP 1 LAST MATERIAL EMPTY
J 0
(-7625 400);
DISPLAY 0.489362 (-7625 400);
PAINT RED (-7625 400);
FORCEPROP 2 LAST CDS_LIB pure_quanta
J 0
(-7675 600);
PAINT MONO (-7675 600);
DISPLAY INVISIBLE (-7675 600);
FORCEPROP 1 LAST PATH I306
J 0
(-7625 750);
DISPLAY 0.978723 (-7625 750);
PAINT WHITE (-7625 750);
DISPLAY INVISIBLE (-7625 750);
FORCEPROP 1 LAST PART_NUMBER CH30106KB19
J 0
(-7625 500);
DISPLAY 0.808511 (-7625 500);
PAINT SKYBLUE (-7625 500);
DISPLAY INVISIBLE (-7625 500);
FORCEADD Q_CAP..1
(-8000 600);
FORCEPROP 1 LAST LOCATION C207
J 0
(-7950 700);
DISPLAY 0.489362 (-7950 700);
PAINT SKYBLUE (-7950 700);
FORCEPROP 0 LAST $SEC 1
J 0
(-7950 750);
PAINT MONO (-7950 750);
DISPLAY INVISIBLE (-7950 750);
FORCEPROP 0 LAST CDS_SEC 1
J 0
(-7950 750);
PAINT MONO (-7950 750);
DISPLAY INVISIBLE (-7950 750);
FORCEPROP 1 LASTPIN (-8000 700) $PN 1
J 0
(-7990 680);
DISPLAY 0.489362 (-7990 680);
PAINT GREEN (-7990 680);
FORCEPROP 1 LASTPIN (-8000 500) $PN 2
J 0
(-7990 480);
DISPLAY 0.489362 (-7990 480);
PAINT GREEN (-7990 480);
FORCEPROP 1 LAST PACK_TYPE C0402
J 0
(-7950 450);
DISPLAY 0.489362 (-7950 450);
PAINT SKYBLUE (-7950 450);
FORCEPROP 1 LAST VOLTAGE 50V
J 0
(-7950 600);
DISPLAY 0.489362 (-7950 600);
PAINT SKYBLUE (-7950 600);
FORCEPROP 1 LAST VALUE 0.001UF
J 0
(-7950 650);
DISPLAY 0.489362 (-7950 650);
PAINT SKYBLUE (-7950 650);
FORCEPROP 1 LAST TOLERANCE 10%
J 0
(-7950 550);
DISPLAY 0.489362 (-7950 550);
PAINT SKYBLUE (-7950 550);
FORCEPROP 1 LAST MATERIAL EMPTY
J 0
(-7950 400);
DISPLAY 0.489362 (-7950 400);
PAINT RED (-7950 400);
FORCEPROP 2 LAST CDS_LIB pure_quanta
J 0
(-8000 600);
PAINT MONO (-8000 600);
DISPLAY INVISIBLE (-8000 600);
FORCEPROP 1 LAST PATH I307
J 0
(-7950 750);
DISPLAY 0.978723 (-7950 750);
PAINT WHITE (-7950 750);
DISPLAY INVISIBLE (-7950 750);
FORCEPROP 1 LAST PART_NUMBER CH30106KB19
J 0
(-7950 500);
DISPLAY 0.808511 (-7950 500);
PAINT SKYBLUE (-7950 500);
DISPLAY INVISIBLE (-7950 500);
FORCEADD GND..1
(-7350 300);
FORCEPROP 3 LASTPIN (-7350 350) SIG_NAME GND\g
J 0
(-7340 360);
DISPLAY 0.659574 (-7340 360);
PAINT MONO (-7340 360);
DISPLAY INVISIBLE (-7340 360);
FORCEPROP 2 LAST CDS_LIB pure_quanta_power
J 0
(-7350 300);
DISPLAY INVISIBLE (-7350 300);
FORCEPROP 1 LAST SIZE 1B
J 0
(-7275 250);
DISPLAY 0.872340 (-7275 250);
PAINT GREEN (-7275 250);
DISPLAY INVISIBLE (-7275 250);
FORCEPROP 1 LAST HDL_POWER GND
J 0
(-7350 450);
DISPLAY 0.872340 (-7350 450);
PAINT GREEN (-7350 450);
DISPLAY INVISIBLE (-7350 450);
FORCEPROP 1 LAST PATH I308
J 0
(-7275 300);
DISPLAY 0.872340 (-7275 300);
PAINT AQUA (-7275 300);
DISPLAY INVISIBLE (-7275 300);
FORCEADD GND..1
(-7025 300);
FORCEPROP 3 LASTPIN (-7025 350) SIG_NAME GND\g
J 0
(-7015 360);
DISPLAY 0.659574 (-7015 360);
PAINT MONO (-7015 360);
DISPLAY INVISIBLE (-7015 360);
FORCEPROP 2 LAST CDS_LIB pure_quanta_power
J 0
(-7025 300);
DISPLAY INVISIBLE (-7025 300);
FORCEPROP 1 LAST SIZE 1B
J 0
(-6950 250);
DISPLAY 0.872340 (-6950 250);
PAINT GREEN (-6950 250);
DISPLAY INVISIBLE (-6950 250);
FORCEPROP 1 LAST HDL_POWER GND
J 0
(-7025 450);
DISPLAY 0.872340 (-7025 450);
PAINT GREEN (-7025 450);
DISPLAY INVISIBLE (-7025 450);
FORCEPROP 1 LAST PATH I309
J 0
(-6950 300);
DISPLAY 0.872340 (-6950 300);
PAINT AQUA (-6950 300);
DISPLAY INVISIBLE (-6950 300);
FORCEADD GND..1
(-8000 300);
FORCEPROP 3 LASTPIN (-8000 350) SIG_NAME GND\g
J 0
(-7990 360);
DISPLAY 0.659574 (-7990 360);
PAINT MONO (-7990 360);
DISPLAY INVISIBLE (-7990 360);
FORCEPROP 2 LAST CDS_LIB pure_quanta_power
J 0
(-8000 300);
DISPLAY INVISIBLE (-8000 300);
FORCEPROP 1 LAST SIZE 1B
J 0
(-7925 250);
DISPLAY 0.872340 (-7925 250);
PAINT GREEN (-7925 250);
DISPLAY INVISIBLE (-7925 250);
FORCEPROP 1 LAST HDL_POWER GND
J 0
(-8000 450);
DISPLAY 0.872340 (-8000 450);
PAINT GREEN (-8000 450);
DISPLAY INVISIBLE (-8000 450);
FORCEPROP 1 LAST PATH I310
J 0
(-7925 300);
DISPLAY 0.872340 (-7925 300);
PAINT AQUA (-7925 300);
DISPLAY INVISIBLE (-7925 300);
FORCEADD GND..1
(-7675 300);
FORCEPROP 3 LASTPIN (-7675 350) SIG_NAME GND\g
J 0
(-7665 360);
DISPLAY 0.659574 (-7665 360);
PAINT MONO (-7665 360);
DISPLAY INVISIBLE (-7665 360);
FORCEPROP 1 LAST SIZE 1B
J 0
(-7600 250);
DISPLAY 0.872340 (-7600 250);
PAINT GREEN (-7600 250);
DISPLAY INVISIBLE (-7600 250);
FORCEPROP 2 LAST CDS_LIB pure_quanta_power
J 0
(-7675 300);
DISPLAY INVISIBLE (-7675 300);
FORCEPROP 1 LAST HDL_POWER GND
J 0
(-7675 450);
DISPLAY 0.872340 (-7675 450);
PAINT GREEN (-7675 450);
DISPLAY INVISIBLE (-7675 450);
FORCEPROP 1 LAST PATH I311
J 0
(-7600 300);
DISPLAY 0.872340 (-7600 300);
PAINT AQUA (-7600 300);
DISPLAY INVISIBLE (-7600 300);
FORCEADD OFFPAGE..2
R 2
(-8775 1100);
FORCEPROP 2 LAST $XR1 174 
J 0
(-9119 1100);
DISPLAY 0.638298 (-9119 1100);
PAINT MONO (-9119 1100);
FORCEPROP 2 LAST $XR0 27 
J 0
(-8999 1100);
DISPLAY 0.638298 (-8999 1100);
PAINT MONO (-8999 1100);
FORCEPROP 2 LAST CDS_LIB standard
J 2
(-8775 1100);
DISPLAY INVISIBLE (-8775 1100);
FORCEPROP 1 LAST OFFPAGE TRUE
J 2
(-9100 975);
DISPLAY 0.872340 (-9100 975);
PAINT GREEN (-9100 975);
DISPLAY INVISIBLE (-9100 975);
FORCEPROP 1 LAST COMMENT_BODY TRUE
J 2
(-8730 1005);
DISPLAY 0.872340 (-8730 1005);
PAINT GREEN (-8730 1005);
DISPLAY INVISIBLE (-8730 1005);
FORCEPROP 2 LAST PATH I312
J 0
(-9025 1150);
DISPLAY 0.680851 (-9025 1150);
DISPLAY INVISIBLE (-9025 1150);
FORCEADD OFFPAGE..2
R 2
(-8775 1000);
FORCEPROP 2 LAST $XR1 27 
J 0
(-9120 1000);
DISPLAY 0.638298 (-9120 1000);
PAINT MONO (-9120 1000);
FORCEPROP 2 LAST $XR0 173 
J 0
(-9030 1000);
DISPLAY 0.638298 (-9030 1000);
PAINT MONO (-9030 1000);
FORCEPROP 2 LAST CDS_LIB standard
J 0
(-8775 1000);
DISPLAY INVISIBLE (-8775 1000);
FORCEPROP 1 LAST OFFPAGE TRUE
J 2
(-9100 875);
DISPLAY 0.872340 (-9100 875);
PAINT GREEN (-9100 875);
DISPLAY INVISIBLE (-9100 875);
FORCEPROP 1 LAST COMMENT_BODY TRUE
J 2
(-8730 905);
DISPLAY 0.872340 (-8730 905);
PAINT GREEN (-8730 905);
DISPLAY INVISIBLE (-8730 905);
FORCEPROP 2 LAST PATH I313
J 0
(-9025 1050);
DISPLAY 0.680851 (-9025 1050);
DISPLAY INVISIBLE (-9025 1050);
FORCEADD OFFPAGE..2
R 2
(-8775 1050);
FORCEPROP 2 LAST $XR1 27 
J 0
(-9120 1050);
DISPLAY 0.638298 (-9120 1050);
PAINT MONO (-9120 1050);
FORCEPROP 2 LAST $XR0 174 
J 0
(-9030 1050);
DISPLAY 0.638298 (-9030 1050);
PAINT MONO (-9030 1050);
FORCEPROP 2 LAST CDS_LIB standard
J 0
(-8775 1050);
DISPLAY INVISIBLE (-8775 1050);
FORCEPROP 1 LAST OFFPAGE TRUE
J 2
(-9100 925);
DISPLAY 0.872340 (-9100 925);
PAINT GREEN (-9100 925);
DISPLAY INVISIBLE (-9100 925);
FORCEPROP 1 LAST COMMENT_BODY TRUE
J 2
(-8730 955);
DISPLAY 0.872340 (-8730 955);
PAINT GREEN (-8730 955);
DISPLAY INVISIBLE (-8730 955);
FORCEPROP 2 LAST PATH I314
J 0
(-9025 1100);
DISPLAY 0.680851 (-9025 1100);
DISPLAY INVISIBLE (-9025 1100);
FORCEADD OFFPAGE..2
R 2
(-8775 900);
FORCEPROP 2 LAST $XR1 27 
J 0
(-9120 900);
DISPLAY 0.638298 (-9120 900);
PAINT MONO (-9120 900);
FORCEPROP 2 LAST $XR0 173 
J 0
(-9030 900);
DISPLAY 0.638298 (-9030 900);
PAINT MONO (-9030 900);
FORCEPROP 2 LAST CDS_LIB standard
J 0
(-8775 900);
DISPLAY INVISIBLE (-8775 900);
FORCEPROP 1 LAST OFFPAGE TRUE
J 2
(-9100 775);
DISPLAY 0.872340 (-9100 775);
PAINT GREEN (-9100 775);
DISPLAY INVISIBLE (-9100 775);
FORCEPROP 1 LAST COMMENT_BODY TRUE
J 2
(-8730 805);
DISPLAY 0.872340 (-8730 805);
PAINT GREEN (-8730 805);
DISPLAY INVISIBLE (-8730 805);
FORCEPROP 2 LAST PATH I315
J 0
(-9025 950);
DISPLAY 0.680851 (-9025 950);
DISPLAY INVISIBLE (-9025 950);
FORCEADD OFFPAGE..2
R 2
(-8775 950);
FORCEPROP 2 LAST $XR1 27 
J 0
(-9120 950);
DISPLAY 0.638298 (-9120 950);
PAINT MONO (-9120 950);
FORCEPROP 2 LAST $XR0 173 
J 0
(-9030 950);
DISPLAY 0.638298 (-9030 950);
PAINT MONO (-9030 950);
FORCEPROP 2 LAST CDS_LIB standard
J 0
(-8775 950);
DISPLAY INVISIBLE (-8775 950);
FORCEPROP 1 LAST OFFPAGE TRUE
J 2
(-9100 825);
DISPLAY 0.872340 (-9100 825);
PAINT GREEN (-9100 825);
DISPLAY INVISIBLE (-9100 825);
FORCEPROP 1 LAST COMMENT_BODY TRUE
J 2
(-8730 855);
DISPLAY 0.872340 (-8730 855);
PAINT GREEN (-8730 855);
DISPLAY INVISIBLE (-8730 855);
FORCEPROP 2 LAST PATH I316
J 0
(-9025 1000);
DISPLAY 0.680851 (-9025 1000);
DISPLAY INVISIBLE (-9025 1000);
FORCEADD OFFPAGE..2
R 2
(-8775 850);
FORCEPROP 2 LAST $XR1 27 
J 0
(-9120 850);
DISPLAY 0.638298 (-9120 850);
PAINT MONO (-9120 850);
FORCEPROP 2 LAST $XR0 173 
J 0
(-9030 850);
DISPLAY 0.638298 (-9030 850);
PAINT MONO (-9030 850);
FORCEPROP 2 LAST CDS_LIB standard
J 0
(-8775 850);
DISPLAY INVISIBLE (-8775 850);
FORCEPROP 1 LAST OFFPAGE TRUE
J 2
(-9100 725);
DISPLAY 0.872340 (-9100 725);
PAINT GREEN (-9100 725);
DISPLAY INVISIBLE (-9100 725);
FORCEPROP 1 LAST COMMENT_BODY TRUE
J 2
(-8730 755);
DISPLAY 0.872340 (-8730 755);
PAINT GREEN (-8730 755);
DISPLAY INVISIBLE (-8730 755);
FORCEPROP 2 LAST PATH I317
J 0
(-9025 900);
DISPLAY 0.680851 (-9025 900);
DISPLAY INVISIBLE (-9025 900);
FORCEADD Q_RES..1
(-6350 5325);
FORCEPROP 1 LAST LOCATION PR59
J 0
(-6550 5325);
DISPLAY 0.489362 (-6550 5325);
PAINT SKYBLUE (-6550 5325);
FORCEPROP 0 LAST $SEC 1
J 0
(-5950 5450);
DISPLAY 0.680851 (-5950 5450);
PAINT MONO (-5950 5450);
DISPLAY INVISIBLE (-5950 5450);
FORCEPROP 0 LAST CDS_SEC 1
J 0
(-5950 5450);
DISPLAY 1.021277 (-5950 5450);
DISPLAY INVISIBLE (-5950 5450);
FORCEPROP 1 LASTPIN (-6450 5325) $PN 1
J 0
(-6438 5337);
DISPLAY 0.489362 (-6438 5337);
PAINT MONO (-6438 5337);
FORCEPROP 1 LASTPIN (-6250 5325) $PN 2
J 0
(-6288 5337);
DISPLAY 0.489362 (-6288 5337);
PAINT MONO (-6288 5337);
FORCEPROP 1 LAST VALUE 0
J 2
(-6200 5325);
DISPLAY 0.489362 (-6200 5325);
PAINT SKYBLUE (-6200 5325);
FORCEPROP 2 LAST CDS_LIB pure_quanta
J 0
(-6350 5325);
DISPLAY INVISIBLE (-6350 5325);
FORCEPROP 1 LAST WATTAGE 1/16W
J 2
(-5950 5425);
DISPLAY 0.489362 (-5950 5425);
PAINT SKYBLUE (-5950 5425);
DISPLAY INVISIBLE (-5950 5425);
FORCEPROP 1 LAST MATERIAL CHIP
J 0
(-6225 5425);
DISPLAY 0.489362 (-6225 5425);
PAINT SKYBLUE (-6225 5425);
DISPLAY INVISIBLE (-6225 5425);
FORCEPROP 1 LAST TOLERANCE 5%
J 0
(-5825 5375);
DISPLAY 0.489362 (-5825 5375);
PAINT SKYBLUE (-5825 5375);
DISPLAY INVISIBLE (-5825 5375);
FORCEPROP 1 LAST PACK_TYPE 0402LF
J 0
(-5750 5375);
DISPLAY 0.489362 (-5750 5375);
PAINT SKYBLUE (-5750 5375);
DISPLAY INVISIBLE (-5750 5375);
FORCEPROP 1 LAST PATH I318
J 0
(-6400 5475);
DISPLAY 0.978723 (-6400 5475);
PAINT WHITE (-6400 5475);
DISPLAY INVISIBLE (-6400 5475);
FORCEPROP 1 LAST PART_NUMBER CS00002JB13
J 0
(-6225 5375);
DISPLAY 0.489362 (-6225 5375);
PAINT SKYBLUE (-6225 5375);
DISPLAY INVISIBLE (-6225 5375);
FORCEADD Q_RES..1
(-6350 5275);
FORCEPROP 1 LAST LOCATION PR60
J 0
(-6550 5275);
DISPLAY 0.489362 (-6550 5275);
PAINT SKYBLUE (-6550 5275);
FORCEPROP 0 LAST $SEC 1
J 0
(-6400 5375);
DISPLAY 0.680851 (-6400 5375);
PAINT MONO (-6400 5375);
DISPLAY INVISIBLE (-6400 5375);
FORCEPROP 0 LAST CDS_SEC 1
J 0
(-6400 5375);
DISPLAY 1.021277 (-6400 5375);
DISPLAY INVISIBLE (-6400 5375);
FORCEPROP 1 LASTPIN (-6450 5275) $PN 1
J 0
(-6438 5287);
DISPLAY 0.489362 (-6438 5287);
PAINT MONO (-6438 5287);
FORCEPROP 1 LASTPIN (-6250 5275) $PN 2
J 0
(-6288 5287);
DISPLAY 0.489362 (-6288 5287);
PAINT MONO (-6288 5287);
FORCEPROP 1 LAST VALUE 0
J 2
(-6200 5275);
DISPLAY 0.489362 (-6200 5275);
PAINT SKYBLUE (-6200 5275);
FORCEPROP 2 LAST CDS_LIB pure_quanta
J 0
(-6350 5275);
DISPLAY INVISIBLE (-6350 5275);
FORCEPROP 1 LAST WATTAGE 1/16W
J 2
(-5950 5375);
DISPLAY 0.489362 (-5950 5375);
PAINT SKYBLUE (-5950 5375);
DISPLAY INVISIBLE (-5950 5375);
FORCEPROP 1 LAST MATERIAL CHIP
J 0
(-6225 5375);
DISPLAY 0.489362 (-6225 5375);
PAINT SKYBLUE (-6225 5375);
DISPLAY INVISIBLE (-6225 5375);
FORCEPROP 1 LAST TOLERANCE 5%
J 0
(-5825 5325);
DISPLAY 0.489362 (-5825 5325);
PAINT SKYBLUE (-5825 5325);
DISPLAY INVISIBLE (-5825 5325);
FORCEPROP 1 LAST PACK_TYPE 0402LF
J 0
(-5750 5325);
DISPLAY 0.489362 (-5750 5325);
PAINT SKYBLUE (-5750 5325);
DISPLAY INVISIBLE (-5750 5325);
FORCEPROP 1 LAST PATH I319
J 0
(-6400 5425);
DISPLAY 0.978723 (-6400 5425);
PAINT WHITE (-6400 5425);
DISPLAY INVISIBLE (-6400 5425);
FORCEPROP 1 LAST PART_NUMBER CS00002JB13
J 0
(-6225 5325);
DISPLAY 0.489362 (-6225 5325);
PAINT SKYBLUE (-6225 5325);
DISPLAY INVISIBLE (-6225 5325);
FORCEADD OFFPAGE..2
R 2
(-7525 5275);
FORCEPROP 2 LAST $XR0 200 
J 0
(-7810 5275);
DISPLAY 0.638298 (-7810 5275);
PAINT MONO (-7810 5275);
FORCEPROP 2 LAST CDS_LIB standard
J 0
(-7525 5275);
DISPLAY INVISIBLE (-7525 5275);
FORCEPROP 1 LAST OFFPAGE TRUE
J 2
(-7850 5150);
DISPLAY 0.872340 (-7850 5150);
PAINT GREEN (-7850 5150);
DISPLAY INVISIBLE (-7850 5150);
FORCEPROP 1 LAST COMMENT_BODY TRUE
J 2
(-7480 5180);
DISPLAY 0.872340 (-7480 5180);
PAINT GREEN (-7480 5180);
DISPLAY INVISIBLE (-7480 5180);
FORCEPROP 2 LAST PATH I320
J 0
(-7475 5350);
DISPLAY 0.680851 (-7475 5350);
DISPLAY INVISIBLE (-7475 5350);
FORCEADD OFFPAGE..2
R 2
(-7525 5325);
FORCEPROP 2 LAST $XR0 200 
J 0
(-7810 5325);
DISPLAY 0.638298 (-7810 5325);
PAINT MONO (-7810 5325);
FORCEPROP 2 LAST CDS_LIB standard
J 0
(-7525 5325);
DISPLAY INVISIBLE (-7525 5325);
FORCEPROP 1 LAST OFFPAGE TRUE
J 2
(-7850 5200);
DISPLAY 0.872340 (-7850 5200);
PAINT GREEN (-7850 5200);
DISPLAY INVISIBLE (-7850 5200);
FORCEPROP 1 LAST COMMENT_BODY TRUE
J 2
(-7480 5230);
DISPLAY 0.872340 (-7480 5230);
PAINT GREEN (-7480 5230);
DISPLAY INVISIBLE (-7480 5230);
FORCEPROP 2 LAST PATH I321
J 0
(-7475 5400);
DISPLAY 0.680851 (-7475 5400);
DISPLAY INVISIBLE (-7475 5400);
FORCEADD Q_RES..1
(-6350 5475);
FORCEPROP 1 LAST LOCATION PR303
J 0
(-6575 5475);
DISPLAY 0.489362 (-6575 5475);
PAINT SKYBLUE (-6575 5475);
FORCEPROP 0 LAST $SEC 1
J 0
(-6400 5550);
DISPLAY 0.680851 (-6400 5550);
PAINT MONO (-6400 5550);
DISPLAY INVISIBLE (-6400 5550);
FORCEPROP 0 LAST CDS_SEC 1
J 0
(-6400 5550);
DISPLAY 1.021277 (-6400 5550);
DISPLAY INVISIBLE (-6400 5550);
FORCEPROP 1 LASTPIN (-6450 5475) $PN 1
J 0
(-6438 5487);
DISPLAY 0.489362 (-6438 5487);
PAINT MONO (-6438 5487);
FORCEPROP 1 LASTPIN (-6250 5475) $PN 2
J 0
(-6288 5487);
DISPLAY 0.489362 (-6288 5487);
PAINT MONO (-6288 5487);
FORCEPROP 1 LAST VALUE 0
J 2
(-6175 5475);
DISPLAY 0.489362 (-6175 5475);
PAINT SKYBLUE (-6175 5475);
FORCEPROP 2 LAST CDS_LIB pure_quanta
J 0
(-6350 5475);
DISPLAY INVISIBLE (-6350 5475);
FORCEPROP 1 LAST WATTAGE 1/16W
J 0
(-6250 5425);
DISPLAY 0.489362 (-6250 5425);
PAINT SKYBLUE (-6250 5425);
DISPLAY INVISIBLE (-6250 5425);
FORCEPROP 1 LAST MATERIAL CHIP
J 0
(-6600 5400);
DISPLAY 0.489362 (-6600 5400);
PAINT SKYBLUE (-6600 5400);
DISPLAY INVISIBLE (-6600 5400);
FORCEPROP 1 LAST TOLERANCE 5%
J 0
(-6225 5500);
DISPLAY 0.489362 (-6225 5500);
PAINT SKYBLUE (-6225 5500);
DISPLAY INVISIBLE (-6225 5500);
FORCEPROP 1 LAST PACK_TYPE 0402LF
J 0
(-6250 5400);
DISPLAY 0.489362 (-6250 5400);
PAINT SKYBLUE (-6250 5400);
DISPLAY INVISIBLE (-6250 5400);
FORCEPROP 1 LAST PATH I322
J 0
(-6400 5625);
DISPLAY 0.978723 (-6400 5625);
PAINT WHITE (-6400 5625);
DISPLAY INVISIBLE (-6400 5625);
FORCEPROP 1 LAST PART_NUMBER CS00002JB13
J 0
(-6600 5425);
DISPLAY 0.489362 (-6600 5425);
PAINT SKYBLUE (-6600 5425);
DISPLAY INVISIBLE (-6600 5425);
FORCEADD Q_RES..1
(-6350 5525);
FORCEPROP 1 LAST LOCATION PR302
J 0
(-6575 5525);
DISPLAY 0.489362 (-6575 5525);
PAINT SKYBLUE (-6575 5525);
FORCEPROP 0 LAST $SEC 1
J 0
(-6400 5600);
DISPLAY 0.680851 (-6400 5600);
PAINT MONO (-6400 5600);
DISPLAY INVISIBLE (-6400 5600);
FORCEPROP 0 LAST CDS_SEC 1
J 0
(-6400 5600);
DISPLAY 1.021277 (-6400 5600);
DISPLAY INVISIBLE (-6400 5600);
FORCEPROP 1 LASTPIN (-6450 5525) $PN 1
J 0
(-6438 5537);
DISPLAY 0.489362 (-6438 5537);
PAINT MONO (-6438 5537);
FORCEPROP 1 LASTPIN (-6250 5525) $PN 2
J 0
(-6288 5537);
DISPLAY 0.489362 (-6288 5537);
PAINT MONO (-6288 5537);
FORCEPROP 1 LAST VALUE 0
J 2
(-6175 5525);
DISPLAY 0.489362 (-6175 5525);
PAINT SKYBLUE (-6175 5525);
FORCEPROP 2 LAST CDS_LIB pure_quanta
J 0
(-6350 5525);
DISPLAY INVISIBLE (-6350 5525);
FORCEPROP 1 LAST WATTAGE 1/16W
J 0
(-6250 5475);
DISPLAY 0.489362 (-6250 5475);
PAINT SKYBLUE (-6250 5475);
DISPLAY INVISIBLE (-6250 5475);
FORCEPROP 1 LAST MATERIAL CHIP
J 0
(-6600 5450);
DISPLAY 0.489362 (-6600 5450);
PAINT SKYBLUE (-6600 5450);
DISPLAY INVISIBLE (-6600 5450);
FORCEPROP 1 LAST TOLERANCE 5%
J 0
(-6225 5550);
DISPLAY 0.489362 (-6225 5550);
PAINT SKYBLUE (-6225 5550);
DISPLAY INVISIBLE (-6225 5550);
FORCEPROP 1 LAST PACK_TYPE 0402LF
J 0
(-6250 5450);
DISPLAY 0.489362 (-6250 5450);
PAINT SKYBLUE (-6250 5450);
DISPLAY INVISIBLE (-6250 5450);
FORCEPROP 1 LAST PATH I323
J 0
(-6400 5675);
DISPLAY 0.978723 (-6400 5675);
PAINT WHITE (-6400 5675);
DISPLAY INVISIBLE (-6400 5675);
FORCEPROP 1 LAST PART_NUMBER CS00002JB13
J 0
(-6600 5475);
DISPLAY 0.489362 (-6600 5475);
PAINT SKYBLUE (-6600 5475);
DISPLAY INVISIBLE (-6600 5475);
FORCEADD OFFPAGE..2
R 2
(-7525 5475);
FORCEPROP 2 LAST $XR0 193 
J 0
(-7810 5475);
DISPLAY 0.638298 (-7810 5475);
PAINT MONO (-7810 5475);
FORCEPROP 2 LAST CDS_LIB standard
J 0
(-7525 5475);
DISPLAY INVISIBLE (-7525 5475);
FORCEPROP 1 LAST OFFPAGE TRUE
J 2
(-7850 5350);
DISPLAY 0.872340 (-7850 5350);
PAINT GREEN (-7850 5350);
DISPLAY INVISIBLE (-7850 5350);
FORCEPROP 1 LAST COMMENT_BODY TRUE
J 2
(-7480 5380);
DISPLAY 0.872340 (-7480 5380);
PAINT GREEN (-7480 5380);
DISPLAY INVISIBLE (-7480 5380);
FORCEPROP 2 LAST PATH I324
J 0
(-7475 5550);
DISPLAY 0.680851 (-7475 5550);
DISPLAY INVISIBLE (-7475 5550);
FORCEADD OFFPAGE..2
R 2
(-7525 5525);
FORCEPROP 2 LAST $XR0 193 
J 0
(-7810 5525);
DISPLAY 0.638298 (-7810 5525);
PAINT MONO (-7810 5525);
FORCEPROP 2 LAST CDS_LIB standard
J 0
(-7525 5525);
DISPLAY INVISIBLE (-7525 5525);
FORCEPROP 1 LAST OFFPAGE TRUE
J 2
(-7850 5400);
DISPLAY 0.872340 (-7850 5400);
PAINT GREEN (-7850 5400);
DISPLAY INVISIBLE (-7850 5400);
FORCEPROP 1 LAST COMMENT_BODY TRUE
J 2
(-7480 5430);
DISPLAY 0.872340 (-7480 5430);
PAINT GREEN (-7480 5430);
DISPLAY INVISIBLE (-7480 5430);
FORCEPROP 2 LAST PATH I325
J 0
(-7475 5600);
DISPLAY 0.680851 (-7475 5600);
DISPLAY INVISIBLE (-7475 5600);
FORCEADD Q_RES..1
(-1475 2900);
FORCEPROP 1 LAST LOCATION R483
J 0
(-1375 2900);
DISPLAY 0.489362 (-1375 2900);
PAINT SKYBLUE (-1375 2900);
FORCEPROP 0 LAST $SEC 1
J 0
(-1375 2950);
DISPLAY 0.680851 (-1375 2950);
PAINT MONO (-1375 2950);
DISPLAY INVISIBLE (-1375 2950);
FORCEPROP 0 LAST CDS_SEC 1
J 0
(-1375 2950);
DISPLAY 0.680851 (-1375 2950);
DISPLAY INVISIBLE (-1375 2950);
FORCEPROP 1 LASTPIN (-1575 2900) $PN 1
J 0
(-1563 2912);
DISPLAY 0.489362 (-1563 2912);
PAINT MONO (-1563 2912);
FORCEPROP 1 LASTPIN (-1375 2900) $PN 2
J 0
(-1413 2912);
DISPLAY 0.489362 (-1413 2912);
PAINT MONO (-1413 2912);
FORCEPROP 1 LAST VALUE 0
J 2
(-1575 2900);
DISPLAY 0.489362 (-1575 2900);
PAINT SKYBLUE (-1575 2900);
FORCEPROP 2 LAST CDS_LIB pure_quanta
J 0
(-1475 2900);
DISPLAY INVISIBLE (-1475 2900);
FORCEPROP 1 LAST WATTAGE 1/16W
J 2
(-1075 2825);
DISPLAY 0.489362 (-1075 2825);
PAINT SKYBLUE (-1075 2825);
DISPLAY INVISIBLE (-1075 2825);
FORCEPROP 1 LAST MATERIAL CHIP
J 0
(-1050 2825);
DISPLAY 0.489362 (-1050 2825);
PAINT SKYBLUE (-1050 2825);
DISPLAY INVISIBLE (-1050 2825);
FORCEPROP 1 LAST TOLERANCE 5%
J 0
(-1500 2825);
DISPLAY 0.489362 (-1500 2825);
PAINT SKYBLUE (-1500 2825);
DISPLAY INVISIBLE (-1500 2825);
FORCEPROP 1 LAST PACK_TYPE 0402LF
J 0
(-1425 2825);
DISPLAY 0.489362 (-1425 2825);
PAINT SKYBLUE (-1425 2825);
DISPLAY INVISIBLE (-1425 2825);
FORCEPROP 1 LAST PATH I334
J 0
(-1525 3050);
DISPLAY 0.978723 (-1525 3050);
PAINT WHITE (-1525 3050);
DISPLAY INVISIBLE (-1525 3050);
FORCEPROP 1 LAST PART_NUMBER CS00002JB13
J 0
(-1450 2950);
DISPLAY 0.489362 (-1450 2950);
PAINT SKYBLUE (-1450 2950);
DISPLAY INVISIBLE (-1450 2950);
FORCEADD Q_RES..1
(-1475 2950);
FORCEPROP 1 LAST LOCATION R481
J 0
(-1375 2950);
DISPLAY 0.489362 (-1375 2950);
PAINT SKYBLUE (-1375 2950);
FORCEPROP 0 LAST $SEC 1
J 0
(-1375 3000);
DISPLAY 0.680851 (-1375 3000);
PAINT MONO (-1375 3000);
DISPLAY INVISIBLE (-1375 3000);
FORCEPROP 0 LAST CDS_SEC 1
J 0
(-1375 3000);
DISPLAY 0.680851 (-1375 3000);
DISPLAY INVISIBLE (-1375 3000);
FORCEPROP 1 LASTPIN (-1575 2950) $PN 1
J 0
(-1563 2962);
DISPLAY 0.489362 (-1563 2962);
PAINT MONO (-1563 2962);
FORCEPROP 1 LASTPIN (-1375 2950) $PN 2
J 0
(-1413 2962);
DISPLAY 0.489362 (-1413 2962);
PAINT MONO (-1413 2962);
FORCEPROP 1 LAST VALUE 0
J 2
(-1575 2950);
DISPLAY 0.489362 (-1575 2950);
PAINT SKYBLUE (-1575 2950);
FORCEPROP 2 LAST CDS_LIB pure_quanta
J 0
(-1475 2950);
DISPLAY INVISIBLE (-1475 2950);
FORCEPROP 1 LAST WATTAGE 1/16W
J 2
(-1075 2875);
DISPLAY 0.489362 (-1075 2875);
PAINT SKYBLUE (-1075 2875);
DISPLAY INVISIBLE (-1075 2875);
FORCEPROP 1 LAST MATERIAL CHIP
J 0
(-1050 2875);
DISPLAY 0.489362 (-1050 2875);
PAINT SKYBLUE (-1050 2875);
DISPLAY INVISIBLE (-1050 2875);
FORCEPROP 1 LAST TOLERANCE 5%
J 0
(-1500 2875);
DISPLAY 0.489362 (-1500 2875);
PAINT SKYBLUE (-1500 2875);
DISPLAY INVISIBLE (-1500 2875);
FORCEPROP 1 LAST PACK_TYPE 0402LF
J 0
(-1425 2875);
DISPLAY 0.489362 (-1425 2875);
PAINT SKYBLUE (-1425 2875);
DISPLAY INVISIBLE (-1425 2875);
FORCEPROP 1 LAST PATH I335
J 0
(-1525 3100);
DISPLAY 0.978723 (-1525 3100);
PAINT WHITE (-1525 3100);
DISPLAY INVISIBLE (-1525 3100);
FORCEPROP 1 LAST PART_NUMBER CS00002JB13
J 0
(-1450 3000);
DISPLAY 0.489362 (-1450 3000);
PAINT SKYBLUE (-1450 3000);
DISPLAY INVISIBLE (-1450 3000);
FORCEADD Q_RES..1
(-1475 2850);
FORCEPROP 1 LAST LOCATION R484
J 0
(-1375 2850);
DISPLAY 0.489362 (-1375 2850);
PAINT SKYBLUE (-1375 2850);
FORCEPROP 0 LAST $SEC 1
J 0
(-1375 2900);
DISPLAY 0.680851 (-1375 2900);
PAINT MONO (-1375 2900);
DISPLAY INVISIBLE (-1375 2900);
FORCEPROP 0 LAST CDS_SEC 1
J 0
(-1375 2900);
DISPLAY 0.680851 (-1375 2900);
DISPLAY INVISIBLE (-1375 2900);
FORCEPROP 1 LASTPIN (-1575 2850) $PN 1
J 0
(-1563 2862);
DISPLAY 0.489362 (-1563 2862);
PAINT MONO (-1563 2862);
FORCEPROP 1 LASTPIN (-1375 2850) $PN 2
J 0
(-1413 2862);
DISPLAY 0.489362 (-1413 2862);
PAINT MONO (-1413 2862);
FORCEPROP 1 LAST VALUE 0
J 2
(-1575 2850);
DISPLAY 0.489362 (-1575 2850);
PAINT SKYBLUE (-1575 2850);
FORCEPROP 2 LAST CDS_LIB pure_quanta
J 0
(-1475 2850);
DISPLAY INVISIBLE (-1475 2850);
FORCEPROP 1 LAST WATTAGE 1/16W
J 2
(-1075 2775);
DISPLAY 0.489362 (-1075 2775);
PAINT SKYBLUE (-1075 2775);
DISPLAY INVISIBLE (-1075 2775);
FORCEPROP 1 LAST MATERIAL CHIP
J 0
(-1050 2775);
DISPLAY 0.489362 (-1050 2775);
PAINT SKYBLUE (-1050 2775);
DISPLAY INVISIBLE (-1050 2775);
FORCEPROP 1 LAST TOLERANCE 5%
J 0
(-1500 2775);
DISPLAY 0.489362 (-1500 2775);
PAINT SKYBLUE (-1500 2775);
DISPLAY INVISIBLE (-1500 2775);
FORCEPROP 1 LAST PACK_TYPE 0402LF
J 0
(-1425 2775);
DISPLAY 0.489362 (-1425 2775);
PAINT SKYBLUE (-1425 2775);
DISPLAY INVISIBLE (-1425 2775);
FORCEPROP 1 LAST PATH I336
J 0
(-1525 3000);
DISPLAY 0.978723 (-1525 3000);
PAINT WHITE (-1525 3000);
DISPLAY INVISIBLE (-1525 3000);
FORCEPROP 1 LAST PART_NUMBER CS00002JB13
J 0
(-1450 2900);
DISPLAY 0.489362 (-1450 2900);
PAINT SKYBLUE (-1450 2900);
DISPLAY INVISIBLE (-1450 2900);
FORCEADD Q_RES..1
(-1475 2800);
FORCEPROP 1 LAST LOCATION R485
J 0
(-1375 2800);
DISPLAY 0.489362 (-1375 2800);
PAINT SKYBLUE (-1375 2800);
FORCEPROP 0 LAST $SEC 1
J 0
(-1375 2850);
DISPLAY 0.680851 (-1375 2850);
PAINT MONO (-1375 2850);
DISPLAY INVISIBLE (-1375 2850);
FORCEPROP 0 LAST CDS_SEC 1
J 0
(-1375 2850);
DISPLAY 0.680851 (-1375 2850);
DISPLAY INVISIBLE (-1375 2850);
FORCEPROP 1 LASTPIN (-1575 2800) $PN 1
J 0
(-1563 2812);
DISPLAY 0.489362 (-1563 2812);
PAINT MONO (-1563 2812);
FORCEPROP 1 LASTPIN (-1375 2800) $PN 2
J 0
(-1413 2812);
DISPLAY 0.489362 (-1413 2812);
PAINT MONO (-1413 2812);
FORCEPROP 1 LAST VALUE 0
J 2
(-1575 2800);
DISPLAY 0.489362 (-1575 2800);
PAINT SKYBLUE (-1575 2800);
FORCEPROP 2 LAST CDS_LIB pure_quanta
J 0
(-1475 2800);
DISPLAY INVISIBLE (-1475 2800);
FORCEPROP 1 LAST WATTAGE 1/16W
J 2
(-1075 2725);
DISPLAY 0.489362 (-1075 2725);
PAINT SKYBLUE (-1075 2725);
DISPLAY INVISIBLE (-1075 2725);
FORCEPROP 1 LAST MATERIAL CHIP
J 0
(-1050 2725);
DISPLAY 0.489362 (-1050 2725);
PAINT SKYBLUE (-1050 2725);
DISPLAY INVISIBLE (-1050 2725);
FORCEPROP 1 LAST TOLERANCE 5%
J 0
(-1500 2725);
DISPLAY 0.489362 (-1500 2725);
PAINT SKYBLUE (-1500 2725);
DISPLAY INVISIBLE (-1500 2725);
FORCEPROP 1 LAST PACK_TYPE 0402LF
J 0
(-1425 2725);
DISPLAY 0.489362 (-1425 2725);
PAINT SKYBLUE (-1425 2725);
DISPLAY INVISIBLE (-1425 2725);
FORCEPROP 1 LAST PATH I337
J 0
(-1525 2950);
DISPLAY 0.978723 (-1525 2950);
PAINT WHITE (-1525 2950);
DISPLAY INVISIBLE (-1525 2950);
FORCEPROP 1 LAST PART_NUMBER CS00002JB13
J 0
(-1450 2850);
DISPLAY 0.489362 (-1450 2850);
PAINT SKYBLUE (-1450 2850);
DISPLAY INVISIBLE (-1450 2850);
FORCEADD OFFPAGE..2
R 2
(-2100 2800);
FORCEPROP 2 LAST $XR2 172 
J 0
(-2564 2800);
DISPLAY 0.638298 (-2564 2800);
PAINT MONO (-2564 2800);
FORCEPROP 2 LAST $XR1 82 
J 0
(-2444 2800);
DISPLAY 0.638298 (-2444 2800);
PAINT MONO (-2444 2800);
FORCEPROP 2 LAST $XR0 27 
J 0
(-2354 2800);
DISPLAY 0.638298 (-2354 2800);
PAINT MONO (-2354 2800);
FORCEPROP 2 LAST CDS_LIB standard
J 0
(-2100 2800);
DISPLAY INVISIBLE (-2100 2800);
FORCEPROP 1 LAST OFFPAGE TRUE
J 2
(-2425 2675);
DISPLAY 0.872340 (-2425 2675);
PAINT GREEN (-2425 2675);
DISPLAY INVISIBLE (-2425 2675);
FORCEPROP 1 LAST COMMENT_BODY TRUE
J 2
(-2055 2705);
DISPLAY 0.872340 (-2055 2705);
PAINT PEACH (-2055 2705);
DISPLAY INVISIBLE (-2055 2705);
FORCEPROP 2 LAST PATH I338
J 0
(-2350 2850);
DISPLAY 0.680851 (-2350 2850);
DISPLAY INVISIBLE (-2350 2850);
FORCEADD OFFPAGE..2
R 2
(-2100 2850);
FORCEPROP 2 LAST $XR0 27 
J 0
(-2354 2850);
DISPLAY 0.638298 (-2354 2850);
PAINT MONO (-2354 2850);
FORCEPROP 2 LAST $XR1 82 
J 0
(-2444 2850);
DISPLAY 0.638298 (-2444 2850);
PAINT MONO (-2444 2850);
FORCEPROP 2 LAST $XR2 172 
J 0
(-2564 2850);
DISPLAY 0.638298 (-2564 2850);
PAINT MONO (-2564 2850);
FORCEPROP 2 LAST CDS_LIB standard
J 0
(-2100 2850);
DISPLAY INVISIBLE (-2100 2850);
FORCEPROP 1 LAST OFFPAGE TRUE
J 2
(-2425 2725);
DISPLAY 0.872340 (-2425 2725);
PAINT GREEN (-2425 2725);
DISPLAY INVISIBLE (-2425 2725);
FORCEPROP 1 LAST COMMENT_BODY TRUE
J 2
(-2055 2755);
DISPLAY 0.872340 (-2055 2755);
PAINT PEACH (-2055 2755);
DISPLAY INVISIBLE (-2055 2755);
FORCEPROP 2 LAST PATH I339
J 0
(-2350 2900);
DISPLAY 0.680851 (-2350 2900);
DISPLAY INVISIBLE (-2350 2900);
FORCEADD OFFPAGE..2
R 2
(-2100 2900);
FORCEPROP 2 LAST $XR2 172 
J 0
(-2564 2900);
DISPLAY 0.638298 (-2564 2900);
PAINT MONO (-2564 2900);
FORCEPROP 2 LAST $XR0 27 
J 0
(-2354 2900);
DISPLAY 0.638298 (-2354 2900);
PAINT MONO (-2354 2900);
FORCEPROP 2 LAST $XR1 82 
J 0
(-2444 2900);
DISPLAY 0.638298 (-2444 2900);
PAINT MONO (-2444 2900);
FORCEPROP 2 LAST CDS_LIB standard
J 0
(-2100 2900);
DISPLAY INVISIBLE (-2100 2900);
FORCEPROP 1 LAST OFFPAGE TRUE
J 2
(-2425 2775);
DISPLAY 0.872340 (-2425 2775);
PAINT GREEN (-2425 2775);
DISPLAY INVISIBLE (-2425 2775);
FORCEPROP 1 LAST COMMENT_BODY TRUE
J 2
(-2055 2805);
DISPLAY 0.872340 (-2055 2805);
PAINT PEACH (-2055 2805);
DISPLAY INVISIBLE (-2055 2805);
FORCEPROP 2 LAST PATH I340
J 0
(-2350 2950);
DISPLAY 0.680851 (-2350 2950);
DISPLAY INVISIBLE (-2350 2950);
FORCEADD OFFPAGE..2
R 2
(-2100 2950);
FORCEPROP 2 LAST $XR0 27 
J 0
(-2354 2950);
DISPLAY 0.638298 (-2354 2950);
PAINT MONO (-2354 2950);
FORCEPROP 2 LAST $XR1 82 
J 0
(-2444 2950);
DISPLAY 0.638298 (-2444 2950);
PAINT MONO (-2444 2950);
FORCEPROP 2 LAST CDS_LIB standard
J 0
(-2100 2950);
DISPLAY INVISIBLE (-2100 2950);
FORCEPROP 1 LAST OFFPAGE TRUE
J 2
(-2425 2825);
DISPLAY 0.872340 (-2425 2825);
PAINT GREEN (-2425 2825);
DISPLAY INVISIBLE (-2425 2825);
FORCEPROP 1 LAST COMMENT_BODY TRUE
J 2
(-2055 2855);
DISPLAY 0.872340 (-2055 2855);
PAINT PEACH (-2055 2855);
DISPLAY INVISIBLE (-2055 2855);
FORCEPROP 2 LAST PATH I341
J 0
(-2350 3000);
DISPLAY 0.680851 (-2350 3000);
DISPLAY INVISIBLE (-2350 3000);
FORCEADD OFFPAGE..3
(-1975 4425);
FORCEPROP 2 LAST $XR2 172 
J 0
(-1581 4425);
DISPLAY 0.638298 (-1581 4425);
PAINT MONO (-1581 4425);
FORCEPROP 2 LAST $XR1 82 
J 0
(-1671 4425);
DISPLAY 0.638298 (-1671 4425);
PAINT MONO (-1671 4425);
FORCEPROP 2 LAST $XR0 27 
J 0
(-1761 4425);
DISPLAY 0.638298 (-1761 4425);
PAINT MONO (-1761 4425);
FORCEPROP 2 LAST CDS_LIB standard
J 0
(-1975 4425);
DISPLAY INVISIBLE (-1975 4425);
FORCEPROP 1 LAST OFFPAGE TRUE
J 0
(-1650 4300);
DISPLAY 0.872340 (-1650 4300);
PAINT GREEN (-1650 4300);
DISPLAY INVISIBLE (-1650 4300);
FORCEPROP 1 LAST COMMENT_BODY TRUE
J 0
(-2025 4325);
DISPLAY 0.872340 (-2025 4325);
PAINT GREEN (-2025 4325);
DISPLAY INVISIBLE (-2025 4325);
FORCEPROP 2 LAST PATH I342
J 0
(-1575 4475);
DISPLAY 0.680851 (-1575 4475);
DISPLAY INVISIBLE (-1575 4475);
FORCEADD OFFPAGE..3
(-1975 4575);
FORCEPROP 2 LAST $XR1 82 
J 0
(-1671 4575);
DISPLAY 0.638298 (-1671 4575);
PAINT MONO (-1671 4575);
FORCEPROP 2 LAST $XR0 27 
J 0
(-1761 4575);
DISPLAY 0.638298 (-1761 4575);
PAINT MONO (-1761 4575);
FORCEPROP 2 LAST CDS_LIB standard
J 0
(-1975 4575);
DISPLAY INVISIBLE (-1975 4575);
FORCEPROP 1 LAST OFFPAGE TRUE
J 0
(-1650 4450);
DISPLAY 0.872340 (-1650 4450);
PAINT GREEN (-1650 4450);
DISPLAY INVISIBLE (-1650 4450);
FORCEPROP 1 LAST COMMENT_BODY TRUE
J 0
(-2025 4475);
DISPLAY 0.872340 (-2025 4475);
PAINT GREEN (-2025 4475);
DISPLAY INVISIBLE (-2025 4475);
FORCEPROP 2 LAST PATH I343
J 0
(-1650 4625);
DISPLAY 0.680851 (-1650 4625);
DISPLAY INVISIBLE (-1650 4625);
FORCEADD OFFPAGE..3
(-1975 4525);
FORCEPROP 2 LAST $XR2 172 
J 0
(-1581 4525);
DISPLAY 0.638298 (-1581 4525);
PAINT MONO (-1581 4525);
FORCEPROP 2 LAST $XR1 82 
J 0
(-1671 4525);
DISPLAY 0.638298 (-1671 4525);
PAINT MONO (-1671 4525);
FORCEPROP 2 LAST $XR0 27 
J 0
(-1761 4525);
DISPLAY 0.638298 (-1761 4525);
PAINT MONO (-1761 4525);
FORCEPROP 2 LAST CDS_LIB standard
J 0
(-1975 4525);
DISPLAY INVISIBLE (-1975 4525);
FORCEPROP 1 LAST OFFPAGE TRUE
J 0
(-1650 4400);
DISPLAY 0.872340 (-1650 4400);
PAINT GREEN (-1650 4400);
DISPLAY INVISIBLE (-1650 4400);
FORCEPROP 1 LAST COMMENT_BODY TRUE
J 0
(-2025 4425);
DISPLAY 0.872340 (-2025 4425);
PAINT GREEN (-2025 4425);
DISPLAY INVISIBLE (-2025 4425);
FORCEPROP 2 LAST PATH I344
J 0
(-1575 4575);
DISPLAY 0.680851 (-1575 4575);
DISPLAY INVISIBLE (-1575 4575);
FORCEADD OFFPAGE..3
(-1975 4475);
FORCEPROP 2 LAST $XR2 172 
J 0
(-1581 4475);
DISPLAY 0.638298 (-1581 4475);
PAINT MONO (-1581 4475);
FORCEPROP 2 LAST $XR1 82 
J 0
(-1671 4475);
DISPLAY 0.638298 (-1671 4475);
PAINT MONO (-1671 4475);
FORCEPROP 2 LAST $XR0 27 
J 0
(-1761 4475);
DISPLAY 0.638298 (-1761 4475);
PAINT MONO (-1761 4475);
FORCEPROP 2 LAST CDS_LIB standard
J 0
(-1975 4475);
DISPLAY INVISIBLE (-1975 4475);
FORCEPROP 1 LAST OFFPAGE TRUE
J 0
(-1650 4350);
DISPLAY 0.872340 (-1650 4350);
PAINT GREEN (-1650 4350);
DISPLAY INVISIBLE (-1650 4350);
FORCEPROP 1 LAST COMMENT_BODY TRUE
J 0
(-2025 4375);
DISPLAY 0.872340 (-2025 4375);
PAINT GREEN (-2025 4375);
DISPLAY INVISIBLE (-2025 4375);
FORCEPROP 2 LAST PATH I345
J 0
(-1575 4525);
DISPLAY 0.680851 (-1575 4525);
DISPLAY INVISIBLE (-1575 4525);
FORCEADD Q_RES..1
(-2725 4575);
FORCEPROP 1 LAST LOCATION R156
J 0
(-2625 4575);
DISPLAY 0.489362 (-2625 4575);
PAINT SKYBLUE (-2625 4575);
FORCEPROP 0 LAST $SEC 1
J 0
(-2625 4625);
DISPLAY 0.680851 (-2625 4625);
PAINT MONO (-2625 4625);
DISPLAY INVISIBLE (-2625 4625);
FORCEPROP 0 LAST CDS_SEC 1
J 0
(-2625 4625);
DISPLAY 0.680851 (-2625 4625);
DISPLAY INVISIBLE (-2625 4625);
FORCEPROP 1 LASTPIN (-2825 4575) $PN 1
J 0
(-2813 4587);
DISPLAY 0.489362 (-2813 4587);
PAINT MONO (-2813 4587);
FORCEPROP 1 LASTPIN (-2625 4575) $PN 2
J 0
(-2663 4587);
DISPLAY 0.489362 (-2663 4587);
PAINT MONO (-2663 4587);
FORCEPROP 1 LAST VALUE 0
J 2
(-2825 4575);
DISPLAY 0.489362 (-2825 4575);
PAINT SKYBLUE (-2825 4575);
FORCEPROP 2 LAST CDS_LIB pure_quanta
J 0
(-2725 4575);
DISPLAY INVISIBLE (-2725 4575);
FORCEPROP 1 LAST WATTAGE 1/16W
J 2
(-2325 4500);
DISPLAY 0.489362 (-2325 4500);
PAINT SKYBLUE (-2325 4500);
DISPLAY INVISIBLE (-2325 4500);
FORCEPROP 1 LAST MATERIAL CHIP
J 0
(-2300 4500);
DISPLAY 0.489362 (-2300 4500);
PAINT SKYBLUE (-2300 4500);
DISPLAY INVISIBLE (-2300 4500);
FORCEPROP 1 LAST TOLERANCE 5%
J 0
(-2750 4500);
DISPLAY 0.489362 (-2750 4500);
PAINT SKYBLUE (-2750 4500);
DISPLAY INVISIBLE (-2750 4500);
FORCEPROP 1 LAST PACK_TYPE 0402LF
J 0
(-2675 4500);
DISPLAY 0.489362 (-2675 4500);
PAINT SKYBLUE (-2675 4500);
DISPLAY INVISIBLE (-2675 4500);
FORCEPROP 1 LAST PATH I346
J 0
(-2775 4725);
DISPLAY 0.978723 (-2775 4725);
PAINT WHITE (-2775 4725);
DISPLAY INVISIBLE (-2775 4725);
FORCEPROP 1 LAST PART_NUMBER CS00002JB13
J 0
(-2700 4625);
DISPLAY 0.489362 (-2700 4625);
PAINT SKYBLUE (-2700 4625);
DISPLAY INVISIBLE (-2700 4625);
FORCEADD Q_RES..1
(-2725 4525);
FORCEPROP 1 LAST LOCATION R157
J 0
(-2625 4525);
DISPLAY 0.489362 (-2625 4525);
PAINT SKYBLUE (-2625 4525);
FORCEPROP 0 LAST $SEC 1
J 0
(-2625 4575);
DISPLAY 0.680851 (-2625 4575);
PAINT MONO (-2625 4575);
DISPLAY INVISIBLE (-2625 4575);
FORCEPROP 0 LAST CDS_SEC 1
J 0
(-2625 4575);
DISPLAY 0.680851 (-2625 4575);
DISPLAY INVISIBLE (-2625 4575);
FORCEPROP 1 LASTPIN (-2825 4525) $PN 1
J 0
(-2813 4537);
DISPLAY 0.489362 (-2813 4537);
PAINT MONO (-2813 4537);
FORCEPROP 1 LASTPIN (-2625 4525) $PN 2
J 0
(-2663 4537);
DISPLAY 0.489362 (-2663 4537);
PAINT MONO (-2663 4537);
FORCEPROP 1 LAST VALUE 0
J 2
(-2825 4525);
DISPLAY 0.489362 (-2825 4525);
PAINT SKYBLUE (-2825 4525);
FORCEPROP 2 LAST CDS_LIB pure_quanta
J 0
(-2725 4525);
DISPLAY INVISIBLE (-2725 4525);
FORCEPROP 1 LAST WATTAGE 1/16W
J 2
(-2325 4450);
DISPLAY 0.489362 (-2325 4450);
PAINT SKYBLUE (-2325 4450);
DISPLAY INVISIBLE (-2325 4450);
FORCEPROP 1 LAST MATERIAL CHIP
J 0
(-2300 4450);
DISPLAY 0.489362 (-2300 4450);
PAINT SKYBLUE (-2300 4450);
DISPLAY INVISIBLE (-2300 4450);
FORCEPROP 1 LAST TOLERANCE 5%
J 0
(-2750 4450);
DISPLAY 0.489362 (-2750 4450);
PAINT SKYBLUE (-2750 4450);
DISPLAY INVISIBLE (-2750 4450);
FORCEPROP 1 LAST PACK_TYPE 0402LF
J 0
(-2675 4450);
DISPLAY 0.489362 (-2675 4450);
PAINT SKYBLUE (-2675 4450);
DISPLAY INVISIBLE (-2675 4450);
FORCEPROP 1 LAST PATH I347
J 0
(-2775 4675);
DISPLAY 0.978723 (-2775 4675);
PAINT WHITE (-2775 4675);
DISPLAY INVISIBLE (-2775 4675);
FORCEPROP 1 LAST PART_NUMBER CS00002JB13
J 0
(-2700 4575);
DISPLAY 0.489362 (-2700 4575);
PAINT SKYBLUE (-2700 4575);
DISPLAY INVISIBLE (-2700 4575);
FORCEADD Q_RES..1
(-2725 4425);
FORCEPROP 1 LAST LOCATION R357
J 0
(-2625 4425);
DISPLAY 0.489362 (-2625 4425);
PAINT SKYBLUE (-2625 4425);
FORCEPROP 0 LAST $SEC 1
J 0
(-2625 4475);
DISPLAY 0.680851 (-2625 4475);
PAINT MONO (-2625 4475);
DISPLAY INVISIBLE (-2625 4475);
FORCEPROP 0 LAST CDS_SEC 1
J 0
(-2625 4475);
DISPLAY 0.680851 (-2625 4475);
DISPLAY INVISIBLE (-2625 4475);
FORCEPROP 1 LASTPIN (-2825 4425) $PN 1
J 0
(-2813 4437);
DISPLAY 0.489362 (-2813 4437);
PAINT MONO (-2813 4437);
FORCEPROP 1 LASTPIN (-2625 4425) $PN 2
J 0
(-2663 4437);
DISPLAY 0.489362 (-2663 4437);
PAINT MONO (-2663 4437);
FORCEPROP 1 LAST VALUE 0
J 2
(-2825 4425);
DISPLAY 0.489362 (-2825 4425);
PAINT SKYBLUE (-2825 4425);
FORCEPROP 2 LAST CDS_LIB pure_quanta
J 0
(-2725 4425);
DISPLAY INVISIBLE (-2725 4425);
FORCEPROP 1 LAST PACK_TYPE 0402LF
J 0
(-2675 4350);
DISPLAY 0.489362 (-2675 4350);
PAINT SKYBLUE (-2675 4350);
DISPLAY INVISIBLE (-2675 4350);
FORCEPROP 1 LAST TOLERANCE 5%
J 0
(-2750 4350);
DISPLAY 0.489362 (-2750 4350);
PAINT SKYBLUE (-2750 4350);
DISPLAY INVISIBLE (-2750 4350);
FORCEPROP 1 LAST MATERIAL CHIP
J 0
(-2300 4350);
DISPLAY 0.489362 (-2300 4350);
PAINT SKYBLUE (-2300 4350);
DISPLAY INVISIBLE (-2300 4350);
FORCEPROP 1 LAST WATTAGE 1/16W
J 2
(-2325 4350);
DISPLAY 0.489362 (-2325 4350);
PAINT SKYBLUE (-2325 4350);
DISPLAY INVISIBLE (-2325 4350);
FORCEPROP 1 LAST PATH I348
J 0
(-2775 4575);
DISPLAY 0.978723 (-2775 4575);
PAINT WHITE (-2775 4575);
DISPLAY INVISIBLE (-2775 4575);
FORCEPROP 1 LAST PART_NUMBER CS00002JB13
J 0
(-2700 4475);
DISPLAY 0.489362 (-2700 4475);
PAINT SKYBLUE (-2700 4475);
DISPLAY INVISIBLE (-2700 4475);
FORCEADD Q_RES..1
(-2725 4475);
FORCEPROP 1 LAST LOCATION R356
J 0
(-2625 4475);
DISPLAY 0.489362 (-2625 4475);
PAINT SKYBLUE (-2625 4475);
FORCEPROP 0 LAST $SEC 1
J 0
(-2625 4525);
DISPLAY 0.680851 (-2625 4525);
PAINT MONO (-2625 4525);
DISPLAY INVISIBLE (-2625 4525);
FORCEPROP 0 LAST CDS_SEC 1
J 0
(-2625 4525);
DISPLAY 0.680851 (-2625 4525);
DISPLAY INVISIBLE (-2625 4525);
FORCEPROP 1 LASTPIN (-2825 4475) $PN 1
J 0
(-2813 4487);
DISPLAY 0.489362 (-2813 4487);
PAINT MONO (-2813 4487);
FORCEPROP 1 LASTPIN (-2625 4475) $PN 2
J 0
(-2663 4487);
DISPLAY 0.489362 (-2663 4487);
PAINT MONO (-2663 4487);
FORCEPROP 1 LAST VALUE 0
J 2
(-2825 4475);
DISPLAY 0.489362 (-2825 4475);
PAINT SKYBLUE (-2825 4475);
FORCEPROP 2 LAST CDS_LIB pure_quanta
J 0
(-2725 4475);
DISPLAY INVISIBLE (-2725 4475);
FORCEPROP 1 LAST WATTAGE 1/16W
J 2
(-2325 4400);
DISPLAY 0.489362 (-2325 4400);
PAINT SKYBLUE (-2325 4400);
DISPLAY INVISIBLE (-2325 4400);
FORCEPROP 1 LAST MATERIAL CHIP
J 0
(-2300 4400);
DISPLAY 0.489362 (-2300 4400);
PAINT SKYBLUE (-2300 4400);
DISPLAY INVISIBLE (-2300 4400);
FORCEPROP 1 LAST TOLERANCE 5%
J 0
(-2750 4400);
DISPLAY 0.489362 (-2750 4400);
PAINT SKYBLUE (-2750 4400);
DISPLAY INVISIBLE (-2750 4400);
FORCEPROP 1 LAST PACK_TYPE 0402LF
J 0
(-2675 4400);
DISPLAY 0.489362 (-2675 4400);
PAINT SKYBLUE (-2675 4400);
DISPLAY INVISIBLE (-2675 4400);
FORCEPROP 1 LAST PATH I349
J 0
(-2775 4625);
DISPLAY 0.978723 (-2775 4625);
PAINT WHITE (-2775 4625);
DISPLAY INVISIBLE (-2775 4625);
FORCEPROP 1 LAST PART_NUMBER CS00002JB13
J 0
(-2700 4525);
DISPLAY 0.489362 (-2700 4525);
PAINT SKYBLUE (-2700 4525);
DISPLAY INVISIBLE (-2700 4525);
FORCEADD OFFPAGE..4
(-1575 1625);
FORCEPROP 2 LAST $XR1 81 
J 0
(-1269 1625);
DISPLAY 0.638298 (-1269 1625);
PAINT MONO (-1269 1625);
FORCEPROP 2 LAST $XR0 167 
J 0
(-1389 1625);
DISPLAY 0.638298 (-1389 1625);
PAINT MONO (-1389 1625);
FORCEPROP 2 LAST CDS_LIB standard
J 0
(-1575 1625);
DISPLAY INVISIBLE (-1575 1625);
FORCEPROP 1 LAST OFFPAGE TRUE
J 0
(-1250 1500);
DISPLAY 0.872340 (-1250 1500);
PAINT GREEN (-1250 1500);
DISPLAY INVISIBLE (-1250 1500);
FORCEPROP 1 LAST COMMENT_BODY TRUE
J 0
(-1600 1525);
DISPLAY 0.872340 (-1600 1525);
PAINT GREEN (-1600 1525);
DISPLAY INVISIBLE (-1600 1525);
FORCEPROP 2 LAST PATH I352
J 0
(-1400 1700);
DISPLAY 0.680851 (-1400 1700);
DISPLAY INVISIBLE (-1400 1700);
FORCEADD Q_RES..1
(-2500 1625);
FORCEPROP 1 LAST LOCATION R1204
J 0
(-2550 1675);
DISPLAY 0.489362 (-2550 1675);
PAINT SKYBLUE (-2550 1675);
FORCEPROP 0 LAST $SEC 1
J 0
(-2550 1725);
DISPLAY 0.680851 (-2550 1725);
PAINT MONO (-2550 1725);
DISPLAY INVISIBLE (-2550 1725);
FORCEPROP 0 LAST CDS_SEC 1
J 0
(-2550 1725);
DISPLAY 0.680851 (-2550 1725);
DISPLAY INVISIBLE (-2550 1725);
FORCEPROP 1 LASTPIN (-2600 1625) $PN 1
J 0
(-2588 1637);
DISPLAY 0.489362 (-2588 1637);
PAINT MONO (-2588 1637);
FORCEPROP 1 LASTPIN (-2400 1625) $PN 2
J 0
(-2438 1637);
DISPLAY 0.489362 (-2438 1637);
PAINT MONO (-2438 1637);
FORCEPROP 1 LAST VALUE 0
J 2
(-2600 1625);
DISPLAY 0.489362 (-2600 1625);
PAINT SKYBLUE (-2600 1625);
FORCEPROP 2 LAST CDS_LIB pure_quanta
J 0
(-2500 1625);
DISPLAY INVISIBLE (-2500 1625);
FORCEPROP 1 LAST WATTAGE 1/16W
J 2
(-2100 1550);
DISPLAY 0.489362 (-2100 1550);
PAINT SKYBLUE (-2100 1550);
DISPLAY INVISIBLE (-2100 1550);
FORCEPROP 1 LAST MATERIAL CHIP
J 0
(-2075 1550);
DISPLAY 0.489362 (-2075 1550);
PAINT SKYBLUE (-2075 1550);
DISPLAY INVISIBLE (-2075 1550);
FORCEPROP 1 LAST TOLERANCE 5%
J 0
(-2525 1550);
DISPLAY 0.489362 (-2525 1550);
PAINT SKYBLUE (-2525 1550);
DISPLAY INVISIBLE (-2525 1550);
FORCEPROP 1 LAST PACK_TYPE 0402LF
J 0
(-2450 1550);
DISPLAY 0.489362 (-2450 1550);
PAINT SKYBLUE (-2450 1550);
DISPLAY INVISIBLE (-2450 1550);
FORCEPROP 1 LAST PATH I353
J 0
(-2550 1775);
DISPLAY 0.978723 (-2550 1775);
PAINT WHITE (-2550 1775);
DISPLAY INVISIBLE (-2550 1775);
FORCEPROP 1 LAST PART_NUMBER CS00002JB13
J 0
(-2475 1675);
DISPLAY 0.489362 (-2475 1675);
PAINT SKYBLUE (-2475 1675);
DISPLAY INVISIBLE (-2475 1675);
FORCEADD TP..1
R 6
(-5975 1625);
FORCEPROP 1 LAST LOCATION TP9
J 1
(-5975 1527);
DISPLAY 0.489362 (-5975 1527);
PAINT SKYBLUE (-5975 1527);
FORCEPROP 0 LAST $SEC 1
J 0
(-6000 1600);
DISPLAY 0.680851 (-6000 1600);
PAINT MONO (-6000 1600);
DISPLAY INVISIBLE (-6000 1600);
FORCEPROP 0 LAST CDS_SEC 1
J 0
(-6000 1600);
DISPLAY 1.021277 (-6000 1600);
DISPLAY INVISIBLE (-6000 1600);
FORCEPROP 0 LASTPIN (-5975 1675) $PN 1
R 1
J 0
(-5985 1685);
DISPLAY 0.489362 (-5985 1685);
PAINT MONO (-5985 1685);
FORCEPROP 1 LAST MATERIAL NA
J 0
(-6000 1577);
DISPLAY 0.489362 (-6000 1577);
PAINT SKYBLUE (-6000 1577);
FORCEPROP 1 LAST PACK_TYPE TP
J 1
(-5920 1669);
DISPLAY 0.446809 (-5920 1669);
PAINT SKYBLUE (-5920 1669);
DISPLAY INVISIBLE (-5920 1669);
FORCEPROP 1 LASTPIN (-5975 1675) $PIN_NUMBER ?
J 2
(-5925 1675);
DISPLAY 0.702128 (-5925 1675);
PAINT MONO (-5925 1675);
DISPLAY INVISIBLE (-5925 1675);
FORCEPROP 2 LAST CDS_LIB pure_quanta
J 0
(-5975 1625);
DISPLAY INVISIBLE (-5975 1625);
FORCEPROP 1 LAST PATH I355
J 1
(-5970 1580);
DISPLAY 0.446809 (-5970 1580);
PAINT GREEN (-5970 1580);
DISPLAY INVISIBLE (-5970 1580);
FORCEPROP 1 LAST PART_NUMBER TP30
J 1
(-5920 1649);
DISPLAY 0.446809 (-5920 1649);
PAINT SKYBLUE (-5920 1649);
DISPLAY INVISIBLE (-5920 1649);
FORCEADD TP..1
R 6
(-6125 1625);
FORCEPROP 1 LAST LOCATION TP8
J 1
(-6125 1525);
DISPLAY 0.489362 (-6125 1525);
PAINT SKYBLUE (-6125 1525);
FORCEPROP 0 LAST $SEC 1
J 0
(-6150 1600);
DISPLAY 0.680851 (-6150 1600);
PAINT MONO (-6150 1600);
DISPLAY INVISIBLE (-6150 1600);
FORCEPROP 0 LAST CDS_SEC 1
J 0
(-6150 1600);
DISPLAY 1.021277 (-6150 1600);
DISPLAY INVISIBLE (-6150 1600);
FORCEPROP 0 LASTPIN (-6125 1675) $PN 1
R 1
J 0
(-6135 1685);
DISPLAY 0.489362 (-6135 1685);
PAINT MONO (-6135 1685);
FORCEPROP 1 LAST MATERIAL NA
J 0
(-6150 1577);
DISPLAY 0.489362 (-6150 1577);
PAINT SKYBLUE (-6150 1577);
FORCEPROP 1 LAST PACK_TYPE TP
J 1
(-6070 1669);
DISPLAY 0.446809 (-6070 1669);
PAINT SKYBLUE (-6070 1669);
DISPLAY INVISIBLE (-6070 1669);
FORCEPROP 2 LAST CDS_LIB pure_quanta
J 0
(-6125 1625);
DISPLAY INVISIBLE (-6125 1625);
FORCEPROP 1 LASTPIN (-6125 1675) $PIN_NUMBER ?
J 2
(-6075 1675);
DISPLAY 0.702128 (-6075 1675);
PAINT MONO (-6075 1675);
DISPLAY INVISIBLE (-6075 1675);
FORCEPROP 1 LAST PATH I356
J 1
(-6120 1580);
DISPLAY 0.446809 (-6120 1580);
PAINT GREEN (-6120 1580);
DISPLAY INVISIBLE (-6120 1580);
FORCEPROP 1 LAST PART_NUMBER TP30
J 1
(-6070 1649);
DISPLAY 0.446809 (-6070 1649);
PAINT SKYBLUE (-6070 1649);
DISPLAY INVISIBLE (-6070 1649);
FORCEADD TP..1
R 6
(-6200 1625);
FORCEPROP 1 LAST LOCATION TP7
J 1
(-6200 1525);
DISPLAY 0.489362 (-6200 1525);
PAINT SKYBLUE (-6200 1525);
FORCEPROP 0 LAST $SEC 1
J 0
(-6225 1600);
DISPLAY 0.680851 (-6225 1600);
PAINT MONO (-6225 1600);
DISPLAY INVISIBLE (-6225 1600);
FORCEPROP 0 LAST CDS_SEC 1
J 0
(-6225 1600);
DISPLAY 1.021277 (-6225 1600);
DISPLAY INVISIBLE (-6225 1600);
FORCEPROP 0 LASTPIN (-6200 1675) $PN 1
R 1
J 0
(-6210 1685);
DISPLAY 0.489362 (-6210 1685);
PAINT MONO (-6210 1685);
FORCEPROP 1 LAST MATERIAL NA
J 0
(-6225 1577);
DISPLAY 0.489362 (-6225 1577);
PAINT SKYBLUE (-6225 1577);
FORCEPROP 1 LAST PACK_TYPE TP
J 1
(-6145 1669);
DISPLAY 0.446809 (-6145 1669);
PAINT SKYBLUE (-6145 1669);
DISPLAY INVISIBLE (-6145 1669);
FORCEPROP 1 LASTPIN (-6200 1675) $PIN_NUMBER ?
J 2
(-6150 1675);
DISPLAY 0.702128 (-6150 1675);
PAINT MONO (-6150 1675);
DISPLAY INVISIBLE (-6150 1675);
FORCEPROP 2 LAST CDS_LIB pure_quanta
J 0
(-6200 1625);
DISPLAY INVISIBLE (-6200 1625);
FORCEPROP 1 LAST PATH I357
J 1
(-6195 1580);
DISPLAY 0.446809 (-6195 1580);
PAINT GREEN (-6195 1580);
DISPLAY INVISIBLE (-6195 1580);
FORCEPROP 1 LAST PART_NUMBER TP30
J 1
(-6145 1649);
DISPLAY 0.446809 (-6145 1649);
PAINT SKYBLUE (-6145 1649);
DISPLAY INVISIBLE (-6145 1649);
FORCEADD TP..1
R 6
(-6275 1625);
FORCEPROP 1 LAST LOCATION TP6
J 1
(-6275 1525);
DISPLAY 0.489362 (-6275 1525);
PAINT SKYBLUE (-6275 1525);
FORCEPROP 0 LAST $SEC 1
J 0
(-6300 1600);
DISPLAY 0.680851 (-6300 1600);
PAINT MONO (-6300 1600);
DISPLAY INVISIBLE (-6300 1600);
FORCEPROP 0 LAST CDS_SEC 1
J 0
(-6300 1600);
DISPLAY 1.021277 (-6300 1600);
DISPLAY INVISIBLE (-6300 1600);
FORCEPROP 0 LASTPIN (-6275 1675) $PN 1
R 1
J 0
(-6285 1685);
DISPLAY 0.489362 (-6285 1685);
PAINT MONO (-6285 1685);
FORCEPROP 1 LAST MATERIAL NA
J 0
(-6300 1577);
DISPLAY 0.489362 (-6300 1577);
PAINT SKYBLUE (-6300 1577);
FORCEPROP 1 LAST PACK_TYPE TP
J 1
(-6220 1669);
DISPLAY 0.446809 (-6220 1669);
PAINT SKYBLUE (-6220 1669);
DISPLAY INVISIBLE (-6220 1669);
FORCEPROP 1 LASTPIN (-6275 1675) $PIN_NUMBER ?
J 2
(-6225 1675);
DISPLAY 0.702128 (-6225 1675);
PAINT MONO (-6225 1675);
DISPLAY INVISIBLE (-6225 1675);
FORCEPROP 2 LAST CDS_LIB pure_quanta
J 0
(-6275 1625);
DISPLAY INVISIBLE (-6275 1625);
FORCEPROP 1 LAST PATH I358
J 1
(-6270 1580);
DISPLAY 0.446809 (-6270 1580);
PAINT GREEN (-6270 1580);
DISPLAY INVISIBLE (-6270 1580);
FORCEPROP 1 LAST PART_NUMBER TP30
J 1
(-6220 1649);
DISPLAY 0.446809 (-6220 1649);
PAINT SKYBLUE (-6220 1649);
DISPLAY INVISIBLE (-6220 1649);
FORCEADD TP..1
R 6
(-6350 1625);
FORCEPROP 1 LAST LOCATION TP5
J 1
(-6350 1525);
DISPLAY 0.489362 (-6350 1525);
PAINT SKYBLUE (-6350 1525);
FORCEPROP 0 LAST $SEC 1
J 0
(-6375 1600);
DISPLAY 0.680851 (-6375 1600);
PAINT MONO (-6375 1600);
DISPLAY INVISIBLE (-6375 1600);
FORCEPROP 0 LAST CDS_SEC 1
J 0
(-6375 1600);
DISPLAY 1.021277 (-6375 1600);
DISPLAY INVISIBLE (-6375 1600);
FORCEPROP 0 LASTPIN (-6350 1675) $PN 1
R 1
J 0
(-6360 1685);
DISPLAY 0.489362 (-6360 1685);
PAINT MONO (-6360 1685);
FORCEPROP 1 LAST MATERIAL NA
J 0
(-6375 1577);
DISPLAY 0.489362 (-6375 1577);
PAINT SKYBLUE (-6375 1577);
FORCEPROP 1 LAST PACK_TYPE TP
J 1
(-6295 1669);
DISPLAY 0.446809 (-6295 1669);
PAINT SKYBLUE (-6295 1669);
DISPLAY INVISIBLE (-6295 1669);
FORCEPROP 1 LASTPIN (-6350 1675) $PIN_NUMBER ?
J 2
(-6300 1675);
DISPLAY 0.702128 (-6300 1675);
PAINT MONO (-6300 1675);
DISPLAY INVISIBLE (-6300 1675);
FORCEPROP 2 LAST CDS_LIB pure_quanta
J 0
(-6350 1625);
DISPLAY INVISIBLE (-6350 1625);
FORCEPROP 1 LAST PATH I359
J 1
(-6345 1580);
DISPLAY 0.446809 (-6345 1580);
PAINT GREEN (-6345 1580);
DISPLAY INVISIBLE (-6345 1580);
FORCEPROP 1 LAST PART_NUMBER TP30
J 1
(-6295 1649);
DISPLAY 0.446809 (-6295 1649);
PAINT SKYBLUE (-6295 1649);
DISPLAY INVISIBLE (-6295 1649);
FORCEADD TP..1
R 6
(-6475 1625);
FORCEPROP 1 LAST LOCATION TP4
J 1
(-6475 1525);
DISPLAY 0.489362 (-6475 1525);
PAINT SKYBLUE (-6475 1525);
FORCEPROP 0 LAST $SEC 1
J 0
(-6500 1600);
DISPLAY 0.680851 (-6500 1600);
PAINT MONO (-6500 1600);
DISPLAY INVISIBLE (-6500 1600);
FORCEPROP 0 LAST CDS_SEC 1
J 0
(-6500 1600);
DISPLAY 1.021277 (-6500 1600);
DISPLAY INVISIBLE (-6500 1600);
FORCEPROP 0 LASTPIN (-6475 1675) $PN 1
R 1
J 0
(-6485 1685);
DISPLAY 0.489362 (-6485 1685);
PAINT MONO (-6485 1685);
FORCEPROP 1 LAST MATERIAL NA
J 0
(-6500 1577);
DISPLAY 0.489362 (-6500 1577);
PAINT SKYBLUE (-6500 1577);
FORCEPROP 1 LAST PACK_TYPE TP
J 1
(-6420 1669);
DISPLAY 0.446809 (-6420 1669);
PAINT SKYBLUE (-6420 1669);
DISPLAY INVISIBLE (-6420 1669);
FORCEPROP 1 LASTPIN (-6475 1675) $PIN_NUMBER ?
J 2
(-6425 1675);
DISPLAY 0.702128 (-6425 1675);
PAINT MONO (-6425 1675);
DISPLAY INVISIBLE (-6425 1675);
FORCEPROP 2 LAST CDS_LIB pure_quanta
J 0
(-6475 1625);
DISPLAY INVISIBLE (-6475 1625);
FORCEPROP 1 LAST PATH I360
J 1
(-6470 1580);
DISPLAY 0.446809 (-6470 1580);
PAINT GREEN (-6470 1580);
DISPLAY INVISIBLE (-6470 1580);
FORCEPROP 1 LAST PART_NUMBER TP30
J 1
(-6420 1649);
DISPLAY 0.446809 (-6420 1649);
PAINT SKYBLUE (-6420 1649);
DISPLAY INVISIBLE (-6420 1649);
FORCEADD TP..1
R 6
(-6550 1625);
FORCEPROP 1 LAST LOCATION TP3
J 1
(-6550 1525);
DISPLAY 0.489362 (-6550 1525);
PAINT SKYBLUE (-6550 1525);
FORCEPROP 0 LAST $SEC 1
J 0
(-6575 1600);
DISPLAY 0.680851 (-6575 1600);
PAINT MONO (-6575 1600);
DISPLAY INVISIBLE (-6575 1600);
FORCEPROP 0 LAST CDS_SEC 1
J 0
(-6575 1600);
DISPLAY 1.021277 (-6575 1600);
DISPLAY INVISIBLE (-6575 1600);
FORCEPROP 0 LASTPIN (-6550 1675) $PN 1
R 1
J 0
(-6560 1685);
DISPLAY 0.489362 (-6560 1685);
PAINT MONO (-6560 1685);
FORCEPROP 1 LAST MATERIAL NA
J 0
(-6575 1577);
DISPLAY 0.489362 (-6575 1577);
PAINT SKYBLUE (-6575 1577);
FORCEPROP 1 LAST PACK_TYPE TP
J 1
(-6495 1669);
DISPLAY 0.446809 (-6495 1669);
PAINT SKYBLUE (-6495 1669);
DISPLAY INVISIBLE (-6495 1669);
FORCEPROP 1 LASTPIN (-6550 1675) $PIN_NUMBER ?
J 2
(-6500 1675);
DISPLAY 0.702128 (-6500 1675);
PAINT MONO (-6500 1675);
DISPLAY INVISIBLE (-6500 1675);
FORCEPROP 2 LAST CDS_LIB pure_quanta
J 0
(-6550 1625);
DISPLAY INVISIBLE (-6550 1625);
FORCEPROP 1 LAST PATH I361
J 1
(-6545 1580);
DISPLAY 0.446809 (-6545 1580);
PAINT GREEN (-6545 1580);
DISPLAY INVISIBLE (-6545 1580);
FORCEPROP 1 LAST PART_NUMBER TP30
J 1
(-6495 1649);
DISPLAY 0.446809 (-6495 1649);
PAINT SKYBLUE (-6495 1649);
DISPLAY INVISIBLE (-6495 1649);
FORCEADD TP..1
R 6
(-6625 1625);
FORCEPROP 1 LAST LOCATION TP2
J 1
(-6625 1525);
DISPLAY 0.489362 (-6625 1525);
PAINT SKYBLUE (-6625 1525);
FORCEPROP 0 LAST $SEC 1
J 0
(-6650 1600);
DISPLAY 0.680851 (-6650 1600);
PAINT MONO (-6650 1600);
DISPLAY INVISIBLE (-6650 1600);
FORCEPROP 0 LAST CDS_SEC 1
J 0
(-6650 1600);
DISPLAY 1.021277 (-6650 1600);
DISPLAY INVISIBLE (-6650 1600);
FORCEPROP 0 LASTPIN (-6625 1675) $PN 1
R 1
J 0
(-6635 1685);
DISPLAY 0.489362 (-6635 1685);
PAINT MONO (-6635 1685);
FORCEPROP 1 LAST MATERIAL NA
J 0
(-6650 1577);
DISPLAY 0.489362 (-6650 1577);
PAINT SKYBLUE (-6650 1577);
FORCEPROP 1 LAST PACK_TYPE TP
J 1
(-6570 1669);
DISPLAY 0.446809 (-6570 1669);
PAINT SKYBLUE (-6570 1669);
DISPLAY INVISIBLE (-6570 1669);
FORCEPROP 1 LASTPIN (-6625 1675) $PIN_NUMBER ?
J 2
(-6575 1675);
DISPLAY 0.702128 (-6575 1675);
PAINT MONO (-6575 1675);
DISPLAY INVISIBLE (-6575 1675);
FORCEPROP 2 LAST CDS_LIB pure_quanta
J 0
(-6625 1625);
DISPLAY INVISIBLE (-6625 1625);
FORCEPROP 1 LAST PATH I362
J 1
(-6620 1580);
DISPLAY 0.446809 (-6620 1580);
PAINT GREEN (-6620 1580);
DISPLAY INVISIBLE (-6620 1580);
FORCEPROP 1 LAST PART_NUMBER TP30
J 1
(-6570 1649);
DISPLAY 0.446809 (-6570 1649);
PAINT SKYBLUE (-6570 1649);
DISPLAY INVISIBLE (-6570 1649);
FORCEADD UNIVERSAL_GND..1
(-150 2650);
FORCEPROP 3 LASTPIN (-150 2700) SIG_NAME GND\g
J 0
(-140 2710);
DISPLAY 0.659574 (-140 2710);
PAINT MONO (-140 2710);
DISPLAY INVISIBLE (-140 2710);
FORCEPROP 2 LAST CDS_LIB pure_quanta_power
J 0
(-150 2650);
DISPLAY INVISIBLE (-150 2650);
FORCEPROP 1 LAST HDL_POWER GND
J 1
(-125 2575);
DISPLAY 0.872340 (-125 2575);
PAINT GREEN (-125 2575);
DISPLAY INVISIBLE (-125 2575);
FORCEPROP 1 LAST PATH I364
J 0
(-75 2650);
DISPLAY 0.872340 (-75 2650);
PAINT AQUA (-75 2650);
DISPLAY INVISIBLE (-75 2650);
FORCEADD UNIVERSAL_GND..1
(-150 2025);
FORCEPROP 3 LASTPIN (-150 2075) SIG_NAME GND\g
J 0
(-140 2085);
DISPLAY 0.659574 (-140 2085);
PAINT MONO (-140 2085);
DISPLAY INVISIBLE (-140 2085);
FORCEPROP 2 LAST CDS_LIB pure_quanta_power
J 0
(-150 2025);
DISPLAY INVISIBLE (-150 2025);
FORCEPROP 1 LAST HDL_POWER GND
J 1
(-125 1950);
DISPLAY 0.872340 (-125 1950);
PAINT GREEN (-125 1950);
DISPLAY INVISIBLE (-125 1950);
FORCEPROP 1 LAST PATH I365
J 0
(-75 2025);
DISPLAY 0.872340 (-75 2025);
PAINT AQUA (-75 2025);
DISPLAY INVISIBLE (-75 2025);
FORCEADD UNIVERSAL_POWER..1
(-9050 3400);
FORCEPROP 3 LASTPIN (-9050 3350) SIG_NAME P3V3_AUX\g
J 0
(-9040 3360);
DISPLAY 0.659574 (-9040 3360);
PAINT MONO (-9040 3360);
DISPLAY INVISIBLE (-9040 3360);
FORCEPROP 1 LAST HDL_POWER P3V3_AUX
J 1
(-9050 3450);
DISPLAY 0.489362 (-9050 3450);
PAINT GREEN (-9050 3450);
FORCEPROP 2 LAST CDS_LIB pure_quanta_power
J 0
(-9050 3400);
DISPLAY INVISIBLE (-9050 3400);
FORCEPROP 1 LAST PATH I366
J 0
(-9000 3425);
DISPLAY 0.872340 (-9000 3425);
PAINT AQUA (-9000 3425);
DISPLAY INVISIBLE (-9000 3425);
FORCEADD OFFPAGE..2
(-7725 2950);
FORCEPROP 2 LAST $XR1 82 
J 0
(-7446 2950);
DISPLAY 0.638298 (-7446 2950);
PAINT MONO (-7446 2950);
FORCEPROP 2 LAST $XR0 27 
J 0
(-7536 2950);
DISPLAY 0.638298 (-7536 2950);
PAINT MONO (-7536 2950);
FORCEPROP 2 LAST CDS_LIB standard
J 0
(-7725 2950);
DISPLAY INVISIBLE (-7725 2950);
FORCEPROP 1 LAST OFFPAGE TRUE
J 0
(-7400 2825);
DISPLAY 0.872340 (-7400 2825);
PAINT GREEN (-7400 2825);
DISPLAY INVISIBLE (-7400 2825);
FORCEPROP 1 LAST COMMENT_BODY TRUE
J 0
(-7770 2855);
DISPLAY 0.872340 (-7770 2855);
PAINT PEACH (-7770 2855);
DISPLAY INVISIBLE (-7770 2855);
FORCEPROP 2 LAST PATH I374
J 0
(-7425 3000);
DISPLAY 0.680851 (-7425 3000);
DISPLAY INVISIBLE (-7425 3000);
FORCEADD OFFPAGE..2
(-7725 2900);
FORCEPROP 2 LAST $XR1 82 
J 0
(-7446 2900);
DISPLAY 0.638298 (-7446 2900);
PAINT MONO (-7446 2900);
FORCEPROP 2 LAST $XR0 27 
J 0
(-7536 2900);
DISPLAY 0.638298 (-7536 2900);
PAINT MONO (-7536 2900);
FORCEPROP 2 LAST CDS_LIB standard
J 0
(-7725 2900);
DISPLAY INVISIBLE (-7725 2900);
FORCEPROP 1 LAST OFFPAGE TRUE
J 0
(-7400 2775);
DISPLAY 0.872340 (-7400 2775);
PAINT GREEN (-7400 2775);
DISPLAY INVISIBLE (-7400 2775);
FORCEPROP 1 LAST COMMENT_BODY TRUE
J 0
(-7770 2805);
DISPLAY 0.872340 (-7770 2805);
PAINT PEACH (-7770 2805);
DISPLAY INVISIBLE (-7770 2805);
FORCEPROP 2 LAST PATH I375
J 0
(-7425 2950);
DISPLAY 0.680851 (-7425 2950);
DISPLAY INVISIBLE (-7425 2950);
FORCEADD OFFPAGE..2
(-7725 2850);
FORCEPROP 2 LAST $XR1 82 
J 0
(-7446 2850);
DISPLAY 0.638298 (-7446 2850);
PAINT MONO (-7446 2850);
FORCEPROP 2 LAST $XR0 27 
J 0
(-7536 2850);
DISPLAY 0.638298 (-7536 2850);
PAINT MONO (-7536 2850);
FORCEPROP 2 LAST CDS_LIB standard
J 0
(-7725 2850);
DISPLAY INVISIBLE (-7725 2850);
FORCEPROP 1 LAST OFFPAGE TRUE
J 0
(-7400 2725);
DISPLAY 0.872340 (-7400 2725);
PAINT GREEN (-7400 2725);
DISPLAY INVISIBLE (-7400 2725);
FORCEPROP 1 LAST COMMENT_BODY TRUE
J 0
(-7770 2755);
DISPLAY 0.872340 (-7770 2755);
PAINT PEACH (-7770 2755);
DISPLAY INVISIBLE (-7770 2755);
FORCEPROP 2 LAST PATH I376
J 0
(-7425 2900);
DISPLAY 0.680851 (-7425 2900);
DISPLAY INVISIBLE (-7425 2900);
FORCEADD Q_RES..1
(-575 5400);
FORCEPROP 1 LAST LOCATION R412
J 0
(-825 5400);
DISPLAY 0.489362 (-825 5400);
PAINT SKYBLUE (-825 5400);
FORCEPROP 0 LAST $SEC 1
J 0
(-450 5425);
DISPLAY 0.680851 (-450 5425);
PAINT MONO (-450 5425);
DISPLAY INVISIBLE (-450 5425);
FORCEPROP 0 LAST CDS_SEC 1
J 0
(-450 5425);
DISPLAY 0.680851 (-450 5425);
DISPLAY INVISIBLE (-450 5425);
FORCEPROP 1 LASTPIN (-675 5400) $PN 1
J 0
(-663 5412);
DISPLAY 0.489362 (-663 5412);
PAINT MONO (-663 5412);
FORCEPROP 1 LASTPIN (-475 5400) $PN 2
J 0
(-513 5412);
DISPLAY 0.489362 (-513 5412);
PAINT MONO (-513 5412);
FORCEPROP 1 LAST VALUE 2.2K
J 0
(-450 5400);
DISPLAY 0.489362 (-450 5400);
PAINT SKYBLUE (-450 5400);
FORCEPROP 1 LAST PACK_TYPE 0402LF
J 0
(-325 5250);
DISPLAY 0.978723 (-325 5250);
PAINT SKYBLUE (-325 5250);
DISPLAY INVISIBLE (-325 5250);
FORCEPROP 1 LAST TOLERANCE 5%
J 0
(-575 5300);
DISPLAY 0.978723 (-575 5300);
PAINT SKYBLUE (-575 5300);
DISPLAY INVISIBLE (-575 5300);
FORCEPROP 1 LAST MATERIAL CHIP
J 0
(-575 5250);
DISPLAY 0.978723 (-575 5250);
PAINT SKYBLUE (-575 5250);
DISPLAY INVISIBLE (-575 5250);
FORCEPROP 1 LAST WATTAGE 1/16W
J 2
(-600 5250);
DISPLAY 0.978723 (-600 5250);
PAINT SKYBLUE (-600 5250);
DISPLAY INVISIBLE (-600 5250);
FORCEPROP 2 LAST CDS_LIB pure_quanta
J 0
(-575 5400);
DISPLAY INVISIBLE (-575 5400);
FORCEPROP 1 LAST PATH I377
J 0
(-625 5550);
DISPLAY 0.978723 (-625 5550);
PAINT WHITE (-625 5550);
DISPLAY INVISIBLE (-625 5550);
FORCEPROP 1 LAST PART_NUMBER CS22202JB07
J 0
(-625 5500);
DISPLAY 0.978723 (-625 5500);
PAINT SKYBLUE (-625 5500);
DISPLAY INVISIBLE (-625 5500);
FORCEADD Q_RES..1
(-575 5100);
FORCEPROP 1 LAST LOCATION R418
J 0
(-825 5100);
DISPLAY 0.489362 (-825 5100);
PAINT SKYBLUE (-825 5100);
FORCEPROP 0 LAST $SEC 1
J 0
(-450 5125);
DISPLAY 0.680851 (-450 5125);
PAINT MONO (-450 5125);
DISPLAY INVISIBLE (-450 5125);
FORCEPROP 0 LAST CDS_SEC 1
J 0
(-450 5125);
DISPLAY 0.680851 (-450 5125);
DISPLAY INVISIBLE (-450 5125);
FORCEPROP 1 LASTPIN (-675 5100) $PN 1
J 0
(-663 5112);
DISPLAY 0.489362 (-663 5112);
PAINT MONO (-663 5112);
FORCEPROP 1 LASTPIN (-475 5100) $PN 2
J 0
(-513 5112);
DISPLAY 0.489362 (-513 5112);
PAINT MONO (-513 5112);
FORCEPROP 1 LAST VALUE 2.2K
J 0
(-450 5100);
DISPLAY 0.489362 (-450 5100);
PAINT SKYBLUE (-450 5100);
FORCEPROP 1 LAST PACK_TYPE 0402LF
J 0
(-325 4950);
DISPLAY 0.978723 (-325 4950);
PAINT SKYBLUE (-325 4950);
DISPLAY INVISIBLE (-325 4950);
FORCEPROP 1 LAST TOLERANCE 5%
J 0
(-575 5000);
DISPLAY 0.978723 (-575 5000);
PAINT SKYBLUE (-575 5000);
DISPLAY INVISIBLE (-575 5000);
FORCEPROP 1 LAST MATERIAL CHIP
J 0
(-575 4950);
DISPLAY 0.978723 (-575 4950);
PAINT SKYBLUE (-575 4950);
DISPLAY INVISIBLE (-575 4950);
FORCEPROP 1 LAST WATTAGE 1/16W
J 2
(-600 4950);
DISPLAY 0.978723 (-600 4950);
PAINT SKYBLUE (-600 4950);
DISPLAY INVISIBLE (-600 4950);
FORCEPROP 2 LAST CDS_LIB pure_quanta
J 0
(-575 5100);
DISPLAY INVISIBLE (-575 5100);
FORCEPROP 1 LAST PATH I378
J 0
(-625 5250);
DISPLAY 0.978723 (-625 5250);
PAINT WHITE (-625 5250);
DISPLAY INVISIBLE (-625 5250);
FORCEPROP 1 LAST PART_NUMBER CS22202JB07
J 0
(-625 5200);
DISPLAY 0.978723 (-625 5200);
PAINT SKYBLUE (-625 5200);
DISPLAY INVISIBLE (-625 5200);
FORCEADD Q_RES..1
(-575 5150);
FORCEPROP 1 LAST LOCATION R417
J 0
(-825 5150);
DISPLAY 0.489362 (-825 5150);
PAINT SKYBLUE (-825 5150);
FORCEPROP 0 LAST $SEC 1
J 0
(-450 5175);
DISPLAY 0.680851 (-450 5175);
PAINT MONO (-450 5175);
DISPLAY INVISIBLE (-450 5175);
FORCEPROP 0 LAST CDS_SEC 1
J 0
(-450 5175);
DISPLAY 0.680851 (-450 5175);
DISPLAY INVISIBLE (-450 5175);
FORCEPROP 1 LASTPIN (-675 5150) $PN 1
J 0
(-663 5162);
DISPLAY 0.489362 (-663 5162);
PAINT MONO (-663 5162);
FORCEPROP 1 LASTPIN (-475 5150) $PN 2
J 0
(-513 5162);
DISPLAY 0.489362 (-513 5162);
PAINT MONO (-513 5162);
FORCEPROP 1 LAST VALUE 2.2K
J 0
(-450 5150);
DISPLAY 0.489362 (-450 5150);
PAINT SKYBLUE (-450 5150);
FORCEPROP 1 LAST PACK_TYPE 0402LF
J 0
(-325 5000);
DISPLAY 0.978723 (-325 5000);
PAINT SKYBLUE (-325 5000);
DISPLAY INVISIBLE (-325 5000);
FORCEPROP 1 LAST TOLERANCE 5%
J 0
(-575 5050);
DISPLAY 0.978723 (-575 5050);
PAINT SKYBLUE (-575 5050);
DISPLAY INVISIBLE (-575 5050);
FORCEPROP 1 LAST MATERIAL CHIP
J 0
(-575 5000);
DISPLAY 0.978723 (-575 5000);
PAINT SKYBLUE (-575 5000);
DISPLAY INVISIBLE (-575 5000);
FORCEPROP 1 LAST WATTAGE 1/16W
J 2
(-600 5000);
DISPLAY 0.978723 (-600 5000);
PAINT SKYBLUE (-600 5000);
DISPLAY INVISIBLE (-600 5000);
FORCEPROP 2 LAST CDS_LIB pure_quanta
J 0
(-575 5150);
DISPLAY INVISIBLE (-575 5150);
FORCEPROP 1 LAST PATH I379
J 0
(-625 5300);
DISPLAY 0.978723 (-625 5300);
PAINT WHITE (-625 5300);
DISPLAY INVISIBLE (-625 5300);
FORCEPROP 1 LAST PART_NUMBER CS22202JB07
J 0
(-625 5250);
DISPLAY 0.978723 (-625 5250);
PAINT SKYBLUE (-625 5250);
DISPLAY INVISIBLE (-625 5250);
FORCEADD Q_RES..1
(-575 5600);
FORCEPROP 1 LAST LOCATION R408
J 0
(-825 5600);
DISPLAY 0.489362 (-825 5600);
PAINT SKYBLUE (-825 5600);
FORCEPROP 0 LAST $SEC 1
J 0
(-450 5625);
DISPLAY 0.680851 (-450 5625);
PAINT MONO (-450 5625);
DISPLAY INVISIBLE (-450 5625);
FORCEPROP 0 LAST CDS_SEC 1
J 0
(-450 5625);
DISPLAY 0.680851 (-450 5625);
DISPLAY INVISIBLE (-450 5625);
FORCEPROP 1 LASTPIN (-675 5600) $PN 1
J 0
(-663 5612);
DISPLAY 0.489362 (-663 5612);
PAINT MONO (-663 5612);
FORCEPROP 1 LASTPIN (-475 5600) $PN 2
J 0
(-513 5612);
DISPLAY 0.489362 (-513 5612);
PAINT MONO (-513 5612);
FORCEPROP 1 LAST VALUE 2.2K
J 0
(-450 5600);
DISPLAY 0.489362 (-450 5600);
PAINT SKYBLUE (-450 5600);
FORCEPROP 1 LAST PACK_TYPE 0402LF
J 0
(-325 5450);
DISPLAY 0.978723 (-325 5450);
PAINT SKYBLUE (-325 5450);
DISPLAY INVISIBLE (-325 5450);
FORCEPROP 1 LAST TOLERANCE 5%
J 0
(-575 5500);
DISPLAY 0.978723 (-575 5500);
PAINT SKYBLUE (-575 5500);
DISPLAY INVISIBLE (-575 5500);
FORCEPROP 1 LAST MATERIAL CHIP
J 0
(-575 5450);
DISPLAY 0.978723 (-575 5450);
PAINT SKYBLUE (-575 5450);
DISPLAY INVISIBLE (-575 5450);
FORCEPROP 1 LAST WATTAGE 1/16W
J 2
(-600 5450);
DISPLAY 0.978723 (-600 5450);
PAINT SKYBLUE (-600 5450);
DISPLAY INVISIBLE (-600 5450);
FORCEPROP 2 LAST CDS_LIB pure_quanta
J 0
(-575 5600);
DISPLAY INVISIBLE (-575 5600);
FORCEPROP 1 LAST PATH I380
J 0
(-625 5750);
DISPLAY 0.978723 (-625 5750);
PAINT WHITE (-625 5750);
DISPLAY INVISIBLE (-625 5750);
FORCEPROP 1 LAST PART_NUMBER CS22202JB07
J 0
(-625 5700);
DISPLAY 0.978723 (-625 5700);
PAINT SKYBLUE (-625 5700);
DISPLAY INVISIBLE (-625 5700);
FORCEADD Q_RES..1
(-575 5550);
FORCEPROP 1 LAST LOCATION R409
J 0
(-825 5550);
DISPLAY 0.489362 (-825 5550);
PAINT SKYBLUE (-825 5550);
FORCEPROP 0 LAST $SEC 1
J 0
(-450 5575);
DISPLAY 0.680851 (-450 5575);
PAINT MONO (-450 5575);
DISPLAY INVISIBLE (-450 5575);
FORCEPROP 0 LAST CDS_SEC 1
J 0
(-450 5575);
DISPLAY 0.680851 (-450 5575);
DISPLAY INVISIBLE (-450 5575);
FORCEPROP 1 LASTPIN (-675 5550) $PN 1
J 0
(-663 5562);
DISPLAY 0.489362 (-663 5562);
PAINT MONO (-663 5562);
FORCEPROP 1 LASTPIN (-475 5550) $PN 2
J 0
(-513 5562);
DISPLAY 0.489362 (-513 5562);
PAINT MONO (-513 5562);
FORCEPROP 1 LAST VALUE 2.2K
J 0
(-450 5550);
DISPLAY 0.489362 (-450 5550);
PAINT SKYBLUE (-450 5550);
FORCEPROP 1 LAST PACK_TYPE 0402LF
J 0
(-325 5400);
DISPLAY 0.978723 (-325 5400);
PAINT SKYBLUE (-325 5400);
DISPLAY INVISIBLE (-325 5400);
FORCEPROP 1 LAST TOLERANCE 5%
J 0
(-575 5450);
DISPLAY 0.978723 (-575 5450);
PAINT SKYBLUE (-575 5450);
DISPLAY INVISIBLE (-575 5450);
FORCEPROP 1 LAST MATERIAL CHIP
J 0
(-575 5400);
DISPLAY 0.978723 (-575 5400);
PAINT SKYBLUE (-575 5400);
DISPLAY INVISIBLE (-575 5400);
FORCEPROP 1 LAST WATTAGE 1/16W
J 2
(-600 5400);
DISPLAY 0.978723 (-600 5400);
PAINT SKYBLUE (-600 5400);
DISPLAY INVISIBLE (-600 5400);
FORCEPROP 2 LAST CDS_LIB pure_quanta
J 0
(-575 5550);
DISPLAY INVISIBLE (-575 5550);
FORCEPROP 1 LAST PATH I381
J 0
(-625 5700);
DISPLAY 0.978723 (-625 5700);
PAINT WHITE (-625 5700);
DISPLAY INVISIBLE (-625 5700);
FORCEPROP 1 LAST PART_NUMBER CS22202JB07
J 0
(-625 5650);
DISPLAY 0.978723 (-625 5650);
PAINT SKYBLUE (-625 5650);
DISPLAY INVISIBLE (-625 5650);
FORCEADD Q_RES..1
(-575 5500);
FORCEPROP 1 LAST LOCATION R410
J 0
(-825 5500);
DISPLAY 0.489362 (-825 5500);
PAINT SKYBLUE (-825 5500);
FORCEPROP 0 LAST $SEC 1
J 0
(-450 5525);
DISPLAY 0.680851 (-450 5525);
PAINT MONO (-450 5525);
DISPLAY INVISIBLE (-450 5525);
FORCEPROP 0 LAST CDS_SEC 1
J 0
(-450 5525);
DISPLAY 0.680851 (-450 5525);
DISPLAY INVISIBLE (-450 5525);
FORCEPROP 1 LASTPIN (-675 5500) $PN 1
J 0
(-663 5512);
DISPLAY 0.489362 (-663 5512);
PAINT MONO (-663 5512);
FORCEPROP 1 LASTPIN (-475 5500) $PN 2
J 0
(-513 5512);
DISPLAY 0.489362 (-513 5512);
PAINT MONO (-513 5512);
FORCEPROP 1 LAST VALUE 2.2K
J 0
(-450 5500);
DISPLAY 0.489362 (-450 5500);
PAINT SKYBLUE (-450 5500);
FORCEPROP 1 LAST PACK_TYPE 0402LF
J 0
(-325 5350);
DISPLAY 0.978723 (-325 5350);
PAINT SKYBLUE (-325 5350);
DISPLAY INVISIBLE (-325 5350);
FORCEPROP 1 LAST TOLERANCE 5%
J 0
(-575 5400);
DISPLAY 0.978723 (-575 5400);
PAINT SKYBLUE (-575 5400);
DISPLAY INVISIBLE (-575 5400);
FORCEPROP 1 LAST MATERIAL CHIP
J 0
(-575 5350);
DISPLAY 0.978723 (-575 5350);
PAINT SKYBLUE (-575 5350);
DISPLAY INVISIBLE (-575 5350);
FORCEPROP 1 LAST WATTAGE 1/16W
J 2
(-600 5350);
DISPLAY 0.978723 (-600 5350);
PAINT SKYBLUE (-600 5350);
DISPLAY INVISIBLE (-600 5350);
FORCEPROP 2 LAST CDS_LIB pure_quanta
J 0
(-575 5500);
DISPLAY INVISIBLE (-575 5500);
FORCEPROP 1 LAST PATH I382
J 0
(-625 5650);
DISPLAY 0.978723 (-625 5650);
PAINT WHITE (-625 5650);
DISPLAY INVISIBLE (-625 5650);
FORCEPROP 1 LAST PART_NUMBER CS22202JB07
J 0
(-625 5600);
DISPLAY 0.978723 (-625 5600);
PAINT SKYBLUE (-625 5600);
DISPLAY INVISIBLE (-625 5600);
FORCEADD Q_RES..1
(-575 5450);
FORCEPROP 1 LAST LOCATION R411
J 0
(-825 5450);
DISPLAY 0.489362 (-825 5450);
PAINT SKYBLUE (-825 5450);
FORCEPROP 0 LAST $SEC 1
J 0
(-450 5475);
DISPLAY 0.680851 (-450 5475);
PAINT MONO (-450 5475);
DISPLAY INVISIBLE (-450 5475);
FORCEPROP 0 LAST CDS_SEC 1
J 0
(-450 5475);
DISPLAY 0.680851 (-450 5475);
DISPLAY INVISIBLE (-450 5475);
FORCEPROP 1 LASTPIN (-675 5450) $PN 1
J 0
(-663 5462);
DISPLAY 0.489362 (-663 5462);
PAINT MONO (-663 5462);
FORCEPROP 1 LASTPIN (-475 5450) $PN 2
J 0
(-513 5462);
DISPLAY 0.489362 (-513 5462);
PAINT MONO (-513 5462);
FORCEPROP 1 LAST VALUE 2.2K
J 0
(-450 5450);
DISPLAY 0.489362 (-450 5450);
PAINT SKYBLUE (-450 5450);
FORCEPROP 1 LAST PACK_TYPE 0402LF
J 0
(-325 5300);
DISPLAY 0.978723 (-325 5300);
PAINT SKYBLUE (-325 5300);
DISPLAY INVISIBLE (-325 5300);
FORCEPROP 1 LAST TOLERANCE 5%
J 0
(-575 5350);
DISPLAY 0.978723 (-575 5350);
PAINT SKYBLUE (-575 5350);
DISPLAY INVISIBLE (-575 5350);
FORCEPROP 1 LAST MATERIAL CHIP
J 0
(-575 5300);
DISPLAY 0.978723 (-575 5300);
PAINT SKYBLUE (-575 5300);
DISPLAY INVISIBLE (-575 5300);
FORCEPROP 1 LAST WATTAGE 1/16W
J 2
(-600 5300);
DISPLAY 0.978723 (-600 5300);
PAINT SKYBLUE (-600 5300);
DISPLAY INVISIBLE (-600 5300);
FORCEPROP 2 LAST CDS_LIB pure_quanta
J 0
(-575 5450);
DISPLAY INVISIBLE (-575 5450);
FORCEPROP 1 LAST PATH I383
J 0
(-625 5600);
DISPLAY 0.978723 (-625 5600);
PAINT WHITE (-625 5600);
DISPLAY INVISIBLE (-625 5600);
FORCEPROP 1 LAST PART_NUMBER CS22202JB07
J 0
(-625 5550);
DISPLAY 0.978723 (-625 5550);
PAINT SKYBLUE (-625 5550);
DISPLAY INVISIBLE (-625 5550);
FORCEADD Q_RES..1
(-575 5350);
FORCEPROP 1 LAST LOCATION R413
J 0
(-825 5350);
DISPLAY 0.489362 (-825 5350);
PAINT SKYBLUE (-825 5350);
FORCEPROP 0 LAST $SEC 1
J 0
(-450 5375);
DISPLAY 0.680851 (-450 5375);
PAINT MONO (-450 5375);
DISPLAY INVISIBLE (-450 5375);
FORCEPROP 0 LAST CDS_SEC 1
J 0
(-450 5375);
DISPLAY 0.680851 (-450 5375);
DISPLAY INVISIBLE (-450 5375);
FORCEPROP 1 LASTPIN (-675 5350) $PN 1
J 0
(-663 5362);
DISPLAY 0.489362 (-663 5362);
PAINT MONO (-663 5362);
FORCEPROP 1 LASTPIN (-475 5350) $PN 2
J 0
(-513 5362);
DISPLAY 0.489362 (-513 5362);
PAINT MONO (-513 5362);
FORCEPROP 1 LAST VALUE 2.2K
J 0
(-450 5350);
DISPLAY 0.489362 (-450 5350);
PAINT SKYBLUE (-450 5350);
FORCEPROP 1 LAST PACK_TYPE 0402LF
J 0
(-325 5200);
DISPLAY 0.978723 (-325 5200);
PAINT SKYBLUE (-325 5200);
DISPLAY INVISIBLE (-325 5200);
FORCEPROP 1 LAST TOLERANCE 5%
J 0
(-575 5250);
DISPLAY 0.978723 (-575 5250);
PAINT SKYBLUE (-575 5250);
DISPLAY INVISIBLE (-575 5250);
FORCEPROP 1 LAST MATERIAL CHIP
J 0
(-575 5200);
DISPLAY 0.978723 (-575 5200);
PAINT SKYBLUE (-575 5200);
DISPLAY INVISIBLE (-575 5200);
FORCEPROP 1 LAST WATTAGE 1/16W
J 2
(-600 5200);
DISPLAY 0.978723 (-600 5200);
PAINT SKYBLUE (-600 5200);
DISPLAY INVISIBLE (-600 5200);
FORCEPROP 2 LAST CDS_LIB pure_quanta
J 0
(-575 5350);
DISPLAY INVISIBLE (-575 5350);
FORCEPROP 1 LAST PATH I384
J 0
(-625 5500);
DISPLAY 0.978723 (-625 5500);
PAINT WHITE (-625 5500);
DISPLAY INVISIBLE (-625 5500);
FORCEPROP 1 LAST PART_NUMBER CS22202JB07
J 0
(-625 5450);
DISPLAY 0.978723 (-625 5450);
PAINT SKYBLUE (-625 5450);
DISPLAY INVISIBLE (-625 5450);
FORCEADD Q_RES..1
(-575 5300);
FORCEPROP 1 LAST LOCATION R414
J 0
(-825 5300);
DISPLAY 0.489362 (-825 5300);
PAINT SKYBLUE (-825 5300);
FORCEPROP 0 LAST $SEC 1
J 0
(-450 5325);
DISPLAY 0.680851 (-450 5325);
PAINT MONO (-450 5325);
DISPLAY INVISIBLE (-450 5325);
FORCEPROP 0 LAST CDS_SEC 1
J 0
(-450 5325);
DISPLAY 0.680851 (-450 5325);
DISPLAY INVISIBLE (-450 5325);
FORCEPROP 1 LASTPIN (-675 5300) $PN 1
J 0
(-663 5312);
DISPLAY 0.489362 (-663 5312);
PAINT MONO (-663 5312);
FORCEPROP 1 LASTPIN (-475 5300) $PN 2
J 0
(-513 5312);
DISPLAY 0.489362 (-513 5312);
PAINT MONO (-513 5312);
FORCEPROP 1 LAST VALUE 2.2K
J 0
(-450 5300);
DISPLAY 0.489362 (-450 5300);
PAINT SKYBLUE (-450 5300);
FORCEPROP 1 LAST PACK_TYPE 0402LF
J 0
(-325 5150);
DISPLAY 0.978723 (-325 5150);
PAINT SKYBLUE (-325 5150);
DISPLAY INVISIBLE (-325 5150);
FORCEPROP 1 LAST TOLERANCE 5%
J 0
(-575 5200);
DISPLAY 0.978723 (-575 5200);
PAINT SKYBLUE (-575 5200);
DISPLAY INVISIBLE (-575 5200);
FORCEPROP 1 LAST MATERIAL CHIP
J 0
(-575 5150);
DISPLAY 0.978723 (-575 5150);
PAINT SKYBLUE (-575 5150);
DISPLAY INVISIBLE (-575 5150);
FORCEPROP 1 LAST WATTAGE 1/16W
J 2
(-600 5150);
DISPLAY 0.978723 (-600 5150);
PAINT SKYBLUE (-600 5150);
DISPLAY INVISIBLE (-600 5150);
FORCEPROP 2 LAST CDS_LIB pure_quanta
J 0
(-575 5300);
DISPLAY INVISIBLE (-575 5300);
FORCEPROP 1 LAST PATH I385
J 0
(-625 5450);
DISPLAY 0.978723 (-625 5450);
PAINT WHITE (-625 5450);
DISPLAY INVISIBLE (-625 5450);
FORCEPROP 1 LAST PART_NUMBER CS22202JB07
J 0
(-625 5400);
DISPLAY 0.978723 (-625 5400);
PAINT SKYBLUE (-625 5400);
DISPLAY INVISIBLE (-625 5400);
FORCEADD Q_RES..1
(-575 5250);
FORCEPROP 1 LAST LOCATION R415
J 0
(-825 5250);
DISPLAY 0.489362 (-825 5250);
PAINT SKYBLUE (-825 5250);
FORCEPROP 0 LAST $SEC 1
J 0
(-450 5275);
DISPLAY 0.680851 (-450 5275);
PAINT MONO (-450 5275);
DISPLAY INVISIBLE (-450 5275);
FORCEPROP 0 LAST CDS_SEC 1
J 0
(-450 5275);
DISPLAY 0.680851 (-450 5275);
DISPLAY INVISIBLE (-450 5275);
FORCEPROP 1 LASTPIN (-675 5250) $PN 1
J 0
(-663 5262);
DISPLAY 0.489362 (-663 5262);
PAINT MONO (-663 5262);
FORCEPROP 1 LASTPIN (-475 5250) $PN 2
J 0
(-513 5262);
DISPLAY 0.489362 (-513 5262);
PAINT MONO (-513 5262);
FORCEPROP 1 LAST VALUE 2.2K
J 0
(-450 5250);
DISPLAY 0.489362 (-450 5250);
PAINT SKYBLUE (-450 5250);
FORCEPROP 1 LAST PACK_TYPE 0402LF
J 0
(-325 5100);
DISPLAY 0.978723 (-325 5100);
PAINT SKYBLUE (-325 5100);
DISPLAY INVISIBLE (-325 5100);
FORCEPROP 1 LAST TOLERANCE 5%
J 0
(-575 5150);
DISPLAY 0.978723 (-575 5150);
PAINT SKYBLUE (-575 5150);
DISPLAY INVISIBLE (-575 5150);
FORCEPROP 1 LAST MATERIAL CHIP
J 0
(-575 5100);
DISPLAY 0.978723 (-575 5100);
PAINT SKYBLUE (-575 5100);
DISPLAY INVISIBLE (-575 5100);
FORCEPROP 1 LAST WATTAGE 1/16W
J 2
(-600 5100);
DISPLAY 0.978723 (-600 5100);
PAINT SKYBLUE (-600 5100);
DISPLAY INVISIBLE (-600 5100);
FORCEPROP 2 LAST CDS_LIB pure_quanta
J 0
(-575 5250);
DISPLAY INVISIBLE (-575 5250);
FORCEPROP 1 LAST PATH I386
J 0
(-625 5400);
DISPLAY 0.978723 (-625 5400);
PAINT WHITE (-625 5400);
DISPLAY INVISIBLE (-625 5400);
FORCEPROP 1 LAST PART_NUMBER CS22202JB07
J 0
(-625 5350);
DISPLAY 0.978723 (-625 5350);
PAINT SKYBLUE (-625 5350);
DISPLAY INVISIBLE (-625 5350);
FORCEADD Q_RES..1
(-575 5200);
FORCEPROP 1 LAST LOCATION R416
J 0
(-825 5200);
DISPLAY 0.489362 (-825 5200);
PAINT SKYBLUE (-825 5200);
FORCEPROP 0 LAST $SEC 1
J 0
(-450 5225);
DISPLAY 0.680851 (-450 5225);
PAINT MONO (-450 5225);
DISPLAY INVISIBLE (-450 5225);
FORCEPROP 0 LAST CDS_SEC 1
J 0
(-450 5225);
DISPLAY 0.680851 (-450 5225);
DISPLAY INVISIBLE (-450 5225);
FORCEPROP 1 LASTPIN (-675 5200) $PN 1
J 0
(-663 5212);
DISPLAY 0.489362 (-663 5212);
PAINT MONO (-663 5212);
FORCEPROP 1 LASTPIN (-475 5200) $PN 2
J 0
(-513 5212);
DISPLAY 0.489362 (-513 5212);
PAINT MONO (-513 5212);
FORCEPROP 1 LAST VALUE 2.2K
J 0
(-450 5200);
DISPLAY 0.489362 (-450 5200);
PAINT SKYBLUE (-450 5200);
FORCEPROP 1 LAST PACK_TYPE 0402LF
J 0
(-325 5050);
DISPLAY 0.978723 (-325 5050);
PAINT SKYBLUE (-325 5050);
DISPLAY INVISIBLE (-325 5050);
FORCEPROP 1 LAST TOLERANCE 5%
J 0
(-575 5100);
DISPLAY 0.978723 (-575 5100);
PAINT SKYBLUE (-575 5100);
DISPLAY INVISIBLE (-575 5100);
FORCEPROP 1 LAST MATERIAL CHIP
J 0
(-575 5050);
DISPLAY 0.978723 (-575 5050);
PAINT SKYBLUE (-575 5050);
DISPLAY INVISIBLE (-575 5050);
FORCEPROP 1 LAST WATTAGE 1/16W
J 2
(-600 5050);
DISPLAY 0.978723 (-600 5050);
PAINT SKYBLUE (-600 5050);
DISPLAY INVISIBLE (-600 5050);
FORCEPROP 2 LAST CDS_LIB pure_quanta
J 0
(-575 5200);
DISPLAY INVISIBLE (-575 5200);
FORCEPROP 1 LAST PATH I387
J 0
(-625 5350);
DISPLAY 0.978723 (-625 5350);
PAINT WHITE (-625 5350);
DISPLAY INVISIBLE (-625 5350);
FORCEPROP 1 LAST PART_NUMBER CS22202JB07
J 0
(-625 5300);
DISPLAY 0.978723 (-625 5300);
PAINT SKYBLUE (-625 5300);
DISPLAY INVISIBLE (-625 5300);
FORCEADD Q_RES..1
(-8700 2850);
FORCEPROP 1 LAST LOCATION R387
J 0
(-8950 2850);
DISPLAY 0.489362 (-8950 2850);
PAINT SKYBLUE (-8950 2850);
FORCEPROP 0 LAST $SEC 1
J 0
(-8575 2875);
DISPLAY 0.680851 (-8575 2875);
PAINT MONO (-8575 2875);
DISPLAY INVISIBLE (-8575 2875);
FORCEPROP 0 LAST CDS_SEC 1
J 0
(-8575 2875);
DISPLAY 0.680851 (-8575 2875);
DISPLAY INVISIBLE (-8575 2875);
FORCEPROP 1 LASTPIN (-8800 2850) $PN 1
J 0
(-8788 2862);
DISPLAY 0.489362 (-8788 2862);
PAINT MONO (-8788 2862);
FORCEPROP 1 LASTPIN (-8600 2850) $PN 2
J 0
(-8638 2862);
DISPLAY 0.489362 (-8638 2862);
PAINT MONO (-8638 2862);
FORCEPROP 1 LAST VALUE 2.2K
J 0
(-8575 2850);
DISPLAY 0.489362 (-8575 2850);
PAINT SKYBLUE (-8575 2850);
FORCEPROP 1 LAST PACK_TYPE 0402LF
J 0
(-8450 2700);
DISPLAY 0.978723 (-8450 2700);
PAINT SKYBLUE (-8450 2700);
DISPLAY INVISIBLE (-8450 2700);
FORCEPROP 1 LAST TOLERANCE 5%
J 0
(-8700 2750);
DISPLAY 0.978723 (-8700 2750);
PAINT SKYBLUE (-8700 2750);
DISPLAY INVISIBLE (-8700 2750);
FORCEPROP 1 LAST MATERIAL CHIP
J 0
(-8700 2700);
DISPLAY 0.978723 (-8700 2700);
PAINT SKYBLUE (-8700 2700);
DISPLAY INVISIBLE (-8700 2700);
FORCEPROP 1 LAST WATTAGE 1/16W
J 2
(-8725 2700);
DISPLAY 0.978723 (-8725 2700);
PAINT SKYBLUE (-8725 2700);
DISPLAY INVISIBLE (-8725 2700);
FORCEPROP 2 LAST CDS_LIB pure_quanta
J 0
(-8700 2850);
DISPLAY INVISIBLE (-8700 2850);
FORCEPROP 1 LAST PATH I388
J 0
(-8750 3000);
DISPLAY 0.978723 (-8750 3000);
PAINT WHITE (-8750 3000);
DISPLAY INVISIBLE (-8750 3000);
FORCEPROP 1 LAST PART_NUMBER CS22202JB07
J 0
(-8750 2950);
DISPLAY 0.978723 (-8750 2950);
PAINT SKYBLUE (-8750 2950);
DISPLAY INVISIBLE (-8750 2950);
FORCEADD Q_RES..1
(-8700 2900);
FORCEPROP 1 LAST LOCATION R388
J 0
(-8950 2900);
DISPLAY 0.489362 (-8950 2900);
PAINT SKYBLUE (-8950 2900);
FORCEPROP 0 LAST $SEC 1
J 0
(-8575 2925);
DISPLAY 0.680851 (-8575 2925);
PAINT MONO (-8575 2925);
DISPLAY INVISIBLE (-8575 2925);
FORCEPROP 0 LAST CDS_SEC 1
J 0
(-8575 2925);
DISPLAY 0.680851 (-8575 2925);
DISPLAY INVISIBLE (-8575 2925);
FORCEPROP 1 LASTPIN (-8800 2900) $PN 1
J 0
(-8788 2912);
DISPLAY 0.489362 (-8788 2912);
PAINT MONO (-8788 2912);
FORCEPROP 1 LASTPIN (-8600 2900) $PN 2
J 0
(-8638 2912);
DISPLAY 0.489362 (-8638 2912);
PAINT MONO (-8638 2912);
FORCEPROP 1 LAST VALUE 2.2K
J 0
(-8575 2900);
DISPLAY 0.489362 (-8575 2900);
PAINT SKYBLUE (-8575 2900);
FORCEPROP 1 LAST PACK_TYPE 0402LF
J 0
(-8450 2750);
DISPLAY 0.978723 (-8450 2750);
PAINT SKYBLUE (-8450 2750);
DISPLAY INVISIBLE (-8450 2750);
FORCEPROP 1 LAST TOLERANCE 5%
J 0
(-8700 2800);
DISPLAY 0.978723 (-8700 2800);
PAINT SKYBLUE (-8700 2800);
DISPLAY INVISIBLE (-8700 2800);
FORCEPROP 1 LAST MATERIAL CHIP
J 0
(-8700 2750);
DISPLAY 0.978723 (-8700 2750);
PAINT SKYBLUE (-8700 2750);
DISPLAY INVISIBLE (-8700 2750);
FORCEPROP 1 LAST WATTAGE 1/16W
J 2
(-8725 2750);
DISPLAY 0.978723 (-8725 2750);
PAINT SKYBLUE (-8725 2750);
DISPLAY INVISIBLE (-8725 2750);
FORCEPROP 2 LAST CDS_LIB pure_quanta
J 0
(-8700 2900);
DISPLAY INVISIBLE (-8700 2900);
FORCEPROP 1 LAST PATH I389
J 0
(-8750 3050);
DISPLAY 0.978723 (-8750 3050);
PAINT WHITE (-8750 3050);
DISPLAY INVISIBLE (-8750 3050);
FORCEPROP 1 LAST PART_NUMBER CS22202JB07
J 0
(-8750 3000);
DISPLAY 0.978723 (-8750 3000);
PAINT SKYBLUE (-8750 3000);
DISPLAY INVISIBLE (-8750 3000);
FORCEADD Q_RES..1
(-8700 2950);
FORCEPROP 1 LAST LOCATION R390
J 0
(-8950 2950);
DISPLAY 0.489362 (-8950 2950);
PAINT SKYBLUE (-8950 2950);
FORCEPROP 0 LAST $SEC 1
J 0
(-8575 2975);
DISPLAY 0.680851 (-8575 2975);
PAINT MONO (-8575 2975);
DISPLAY INVISIBLE (-8575 2975);
FORCEPROP 0 LAST CDS_SEC 1
J 0
(-8575 2975);
DISPLAY 0.680851 (-8575 2975);
DISPLAY INVISIBLE (-8575 2975);
FORCEPROP 1 LASTPIN (-8800 2950) $PN 1
J 0
(-8788 2962);
DISPLAY 0.489362 (-8788 2962);
PAINT MONO (-8788 2962);
FORCEPROP 1 LASTPIN (-8600 2950) $PN 2
J 0
(-8638 2962);
DISPLAY 0.489362 (-8638 2962);
PAINT MONO (-8638 2962);
FORCEPROP 1 LAST VALUE 2.2K
J 0
(-8575 2950);
DISPLAY 0.489362 (-8575 2950);
PAINT SKYBLUE (-8575 2950);
FORCEPROP 1 LAST PACK_TYPE 0402LF
J 0
(-8450 2800);
DISPLAY 0.978723 (-8450 2800);
PAINT SKYBLUE (-8450 2800);
DISPLAY INVISIBLE (-8450 2800);
FORCEPROP 1 LAST TOLERANCE 5%
J 0
(-8700 2850);
DISPLAY 0.978723 (-8700 2850);
PAINT SKYBLUE (-8700 2850);
DISPLAY INVISIBLE (-8700 2850);
FORCEPROP 1 LAST MATERIAL CHIP
J 0
(-8700 2800);
DISPLAY 0.978723 (-8700 2800);
PAINT SKYBLUE (-8700 2800);
DISPLAY INVISIBLE (-8700 2800);
FORCEPROP 1 LAST WATTAGE 1/16W
J 2
(-8725 2800);
DISPLAY 0.978723 (-8725 2800);
PAINT SKYBLUE (-8725 2800);
DISPLAY INVISIBLE (-8725 2800);
FORCEPROP 2 LAST CDS_LIB pure_quanta
J 0
(-8700 2950);
DISPLAY INVISIBLE (-8700 2950);
FORCEPROP 1 LAST PATH I390
J 0
(-8750 3100);
DISPLAY 0.978723 (-8750 3100);
PAINT WHITE (-8750 3100);
DISPLAY INVISIBLE (-8750 3100);
FORCEPROP 1 LAST PART_NUMBER CS22202JB07
J 0
(-8750 3050);
DISPLAY 0.978723 (-8750 3050);
PAINT SKYBLUE (-8750 3050);
DISPLAY INVISIBLE (-8750 3050);
FORCEADD Q_RES..1
(-8700 3000);
FORCEPROP 1 LAST LOCATION R389
J 0
(-8950 3000);
DISPLAY 0.489362 (-8950 3000);
PAINT SKYBLUE (-8950 3000);
FORCEPROP 0 LAST $SEC 1
J 0
(-8575 3025);
DISPLAY 0.680851 (-8575 3025);
PAINT MONO (-8575 3025);
DISPLAY INVISIBLE (-8575 3025);
FORCEPROP 0 LAST CDS_SEC 1
J 0
(-8575 3025);
DISPLAY 0.680851 (-8575 3025);
DISPLAY INVISIBLE (-8575 3025);
FORCEPROP 1 LASTPIN (-8800 3000) $PN 1
J 0
(-8788 3012);
DISPLAY 0.489362 (-8788 3012);
PAINT MONO (-8788 3012);
FORCEPROP 1 LASTPIN (-8600 3000) $PN 2
J 0
(-8638 3012);
DISPLAY 0.489362 (-8638 3012);
PAINT MONO (-8638 3012);
FORCEPROP 1 LAST VALUE 2.2K
J 0
(-8575 3000);
DISPLAY 0.489362 (-8575 3000);
PAINT SKYBLUE (-8575 3000);
FORCEPROP 1 LAST PACK_TYPE 0402LF
J 0
(-8450 2850);
DISPLAY 0.978723 (-8450 2850);
PAINT SKYBLUE (-8450 2850);
DISPLAY INVISIBLE (-8450 2850);
FORCEPROP 1 LAST TOLERANCE 5%
J 0
(-8700 2900);
DISPLAY 0.978723 (-8700 2900);
PAINT SKYBLUE (-8700 2900);
DISPLAY INVISIBLE (-8700 2900);
FORCEPROP 1 LAST MATERIAL CHIP
J 0
(-8700 2850);
DISPLAY 0.978723 (-8700 2850);
PAINT SKYBLUE (-8700 2850);
DISPLAY INVISIBLE (-8700 2850);
FORCEPROP 1 LAST WATTAGE 1/16W
J 2
(-8725 2850);
DISPLAY 0.978723 (-8725 2850);
PAINT SKYBLUE (-8725 2850);
DISPLAY INVISIBLE (-8725 2850);
FORCEPROP 2 LAST CDS_LIB pure_quanta
J 0
(-8700 3000);
DISPLAY INVISIBLE (-8700 3000);
FORCEPROP 1 LAST PATH I391
J 0
(-8750 3150);
DISPLAY 0.978723 (-8750 3150);
PAINT WHITE (-8750 3150);
DISPLAY INVISIBLE (-8750 3150);
FORCEPROP 1 LAST PART_NUMBER CS22202JB07
J 0
(-8750 3100);
DISPLAY 0.978723 (-8750 3100);
PAINT SKYBLUE (-8750 3100);
DISPLAY INVISIBLE (-8750 3100);
FORCEADD Q_RES..1
(-8700 3050);
FORCEPROP 1 LAST LOCATION R391
J 0
(-8950 3050);
DISPLAY 0.489362 (-8950 3050);
PAINT SKYBLUE (-8950 3050);
FORCEPROP 0 LAST $SEC 1
J 0
(-8575 3075);
DISPLAY 0.680851 (-8575 3075);
PAINT MONO (-8575 3075);
DISPLAY INVISIBLE (-8575 3075);
FORCEPROP 0 LAST CDS_SEC 1
J 0
(-8575 3075);
DISPLAY 0.680851 (-8575 3075);
DISPLAY INVISIBLE (-8575 3075);
FORCEPROP 1 LASTPIN (-8800 3050) $PN 1
J 0
(-8788 3062);
DISPLAY 0.489362 (-8788 3062);
PAINT MONO (-8788 3062);
FORCEPROP 1 LASTPIN (-8600 3050) $PN 2
J 0
(-8638 3062);
DISPLAY 0.489362 (-8638 3062);
PAINT MONO (-8638 3062);
FORCEPROP 1 LAST VALUE 2.2K
J 0
(-8575 3050);
DISPLAY 0.489362 (-8575 3050);
PAINT SKYBLUE (-8575 3050);
FORCEPROP 1 LAST PACK_TYPE 0402LF
J 0
(-8450 2900);
DISPLAY 0.978723 (-8450 2900);
PAINT SKYBLUE (-8450 2900);
DISPLAY INVISIBLE (-8450 2900);
FORCEPROP 1 LAST TOLERANCE 5%
J 0
(-8700 2950);
DISPLAY 0.978723 (-8700 2950);
PAINT SKYBLUE (-8700 2950);
DISPLAY INVISIBLE (-8700 2950);
FORCEPROP 1 LAST MATERIAL CHIP
J 0
(-8700 2900);
DISPLAY 0.978723 (-8700 2900);
PAINT SKYBLUE (-8700 2900);
DISPLAY INVISIBLE (-8700 2900);
FORCEPROP 1 LAST WATTAGE 1/16W
J 2
(-8725 2900);
DISPLAY 0.978723 (-8725 2900);
PAINT SKYBLUE (-8725 2900);
DISPLAY INVISIBLE (-8725 2900);
FORCEPROP 2 LAST CDS_LIB pure_quanta
J 0
(-8700 3050);
DISPLAY INVISIBLE (-8700 3050);
FORCEPROP 1 LAST PATH I392
J 0
(-8750 3200);
DISPLAY 0.978723 (-8750 3200);
PAINT WHITE (-8750 3200);
DISPLAY INVISIBLE (-8750 3200);
FORCEPROP 1 LAST PART_NUMBER CS22202JB07
J 0
(-8750 3150);
DISPLAY 0.978723 (-8750 3150);
PAINT SKYBLUE (-8750 3150);
DISPLAY INVISIBLE (-8750 3150);
FORCEADD Q_RES..1
(-8700 3100);
FORCEPROP 1 LAST LOCATION R396
J 0
(-8950 3100);
DISPLAY 0.489362 (-8950 3100);
PAINT SKYBLUE (-8950 3100);
FORCEPROP 0 LAST $SEC 1
J 0
(-8575 3125);
DISPLAY 0.680851 (-8575 3125);
PAINT MONO (-8575 3125);
DISPLAY INVISIBLE (-8575 3125);
FORCEPROP 0 LAST CDS_SEC 1
J 0
(-8575 3125);
DISPLAY 0.680851 (-8575 3125);
DISPLAY INVISIBLE (-8575 3125);
FORCEPROP 1 LASTPIN (-8800 3100) $PN 1
J 0
(-8788 3112);
DISPLAY 0.489362 (-8788 3112);
PAINT MONO (-8788 3112);
FORCEPROP 1 LASTPIN (-8600 3100) $PN 2
J 0
(-8638 3112);
DISPLAY 0.489362 (-8638 3112);
PAINT MONO (-8638 3112);
FORCEPROP 1 LAST VALUE 2.2K
J 0
(-8575 3100);
DISPLAY 0.489362 (-8575 3100);
PAINT SKYBLUE (-8575 3100);
FORCEPROP 1 LAST PACK_TYPE 0402LF
J 0
(-8450 2950);
DISPLAY 0.978723 (-8450 2950);
PAINT SKYBLUE (-8450 2950);
DISPLAY INVISIBLE (-8450 2950);
FORCEPROP 1 LAST TOLERANCE 5%
J 0
(-8700 3000);
DISPLAY 0.978723 (-8700 3000);
PAINT SKYBLUE (-8700 3000);
DISPLAY INVISIBLE (-8700 3000);
FORCEPROP 1 LAST MATERIAL CHIP
J 0
(-8700 2950);
DISPLAY 0.978723 (-8700 2950);
PAINT SKYBLUE (-8700 2950);
DISPLAY INVISIBLE (-8700 2950);
FORCEPROP 1 LAST WATTAGE 1/16W
J 2
(-8725 2950);
DISPLAY 0.978723 (-8725 2950);
PAINT SKYBLUE (-8725 2950);
DISPLAY INVISIBLE (-8725 2950);
FORCEPROP 2 LAST CDS_LIB pure_quanta
J 0
(-8700 3100);
DISPLAY INVISIBLE (-8700 3100);
FORCEPROP 1 LAST PATH I393
J 0
(-8750 3250);
DISPLAY 0.978723 (-8750 3250);
PAINT WHITE (-8750 3250);
DISPLAY INVISIBLE (-8750 3250);
FORCEPROP 1 LAST PART_NUMBER CS22202JB07
J 0
(-8750 3200);
DISPLAY 0.978723 (-8750 3200);
PAINT SKYBLUE (-8750 3200);
DISPLAY INVISIBLE (-8750 3200);
FORCEADD Q_RES..1
(-8700 3150);
FORCEPROP 1 LAST LOCATION R397
J 0
(-8950 3150);
DISPLAY 0.489362 (-8950 3150);
PAINT SKYBLUE (-8950 3150);
FORCEPROP 0 LAST $SEC 1
J 0
(-8575 3175);
DISPLAY 0.680851 (-8575 3175);
PAINT MONO (-8575 3175);
DISPLAY INVISIBLE (-8575 3175);
FORCEPROP 0 LAST CDS_SEC 1
J 0
(-8575 3175);
DISPLAY 0.680851 (-8575 3175);
DISPLAY INVISIBLE (-8575 3175);
FORCEPROP 1 LASTPIN (-8800 3150) $PN 1
J 0
(-8788 3162);
DISPLAY 0.489362 (-8788 3162);
PAINT MONO (-8788 3162);
FORCEPROP 1 LASTPIN (-8600 3150) $PN 2
J 0
(-8638 3162);
DISPLAY 0.489362 (-8638 3162);
PAINT MONO (-8638 3162);
FORCEPROP 1 LAST VALUE 2.2K
J 0
(-8575 3150);
DISPLAY 0.489362 (-8575 3150);
PAINT SKYBLUE (-8575 3150);
FORCEPROP 1 LAST PACK_TYPE 0402LF
J 0
(-8450 3000);
DISPLAY 0.978723 (-8450 3000);
PAINT SKYBLUE (-8450 3000);
DISPLAY INVISIBLE (-8450 3000);
FORCEPROP 1 LAST TOLERANCE 5%
J 0
(-8700 3050);
DISPLAY 0.978723 (-8700 3050);
PAINT SKYBLUE (-8700 3050);
DISPLAY INVISIBLE (-8700 3050);
FORCEPROP 1 LAST MATERIAL CHIP
J 0
(-8700 3000);
DISPLAY 0.978723 (-8700 3000);
PAINT SKYBLUE (-8700 3000);
DISPLAY INVISIBLE (-8700 3000);
FORCEPROP 1 LAST WATTAGE 1/16W
J 2
(-8725 3000);
DISPLAY 0.978723 (-8725 3000);
PAINT SKYBLUE (-8725 3000);
DISPLAY INVISIBLE (-8725 3000);
FORCEPROP 2 LAST CDS_LIB pure_quanta
J 0
(-8700 3150);
DISPLAY INVISIBLE (-8700 3150);
FORCEPROP 1 LAST PATH I394
J 0
(-8750 3300);
DISPLAY 0.978723 (-8750 3300);
PAINT WHITE (-8750 3300);
DISPLAY INVISIBLE (-8750 3300);
FORCEPROP 1 LAST PART_NUMBER CS22202JB07
J 0
(-8750 3250);
DISPLAY 0.978723 (-8750 3250);
PAINT SKYBLUE (-8750 3250);
DISPLAY INVISIBLE (-8750 3250);
FORCEADD Q_RES..2
R 2
(-8675 4650);
FORCEPROP 1 LAST LOCATION R392
J 2
(-8725 4725);
DISPLAY 0.489362 (-8725 4725);
PAINT SKYBLUE (-8725 4725);
FORCEPROP 0 LAST $SEC 1
J 0
(-8725 4750);
DISPLAY 0.680851 (-8725 4750);
PAINT MONO (-8725 4750);
DISPLAY INVISIBLE (-8725 4750);
FORCEPROP 0 LAST CDS_SEC 1
J 0
(-8725 4750);
DISPLAY 0.680851 (-8725 4750);
DISPLAY INVISIBLE (-8725 4750);
FORCEPROP 1 LASTPIN (-8675 4750) $PN 1
J 2
(-8680 4712);
DISPLAY 0.489362 (-8680 4712);
PAINT MONO (-8680 4712);
FORCEPROP 1 LASTPIN (-8675 4550) $PN 2
J 2
(-8680 4560);
DISPLAY 0.489362 (-8680 4560);
PAINT MONO (-8680 4560);
FORCEPROP 1 LAST PACK_TYPE 0402LF
J 2
(-8725 4575);
DISPLAY 0.489362 (-8725 4575);
PAINT SKYBLUE (-8725 4575);
FORCEPROP 1 LAST VALUE 2.2K
J 2
(-8725 4675);
DISPLAY 0.489362 (-8725 4675);
PAINT SKYBLUE (-8725 4675);
FORCEPROP 1 LAST MATERIAL EMPTY
J 2
(-8725 4625);
DISPLAY 0.489362 (-8725 4625);
PAINT RED (-8725 4625);
FORCEPROP 1 LAST TOLERANCE 5%
J 2
(-8720 4675);
DISPLAY 0.510638 (-8720 4675);
PAINT SKYBLUE (-8720 4675);
DISPLAY INVISIBLE (-8720 4675);
FORCEPROP 1 LAST WATTAGE 1/16W
J 2
(-8715 4625);
DISPLAY 0.510638 (-8715 4625);
PAINT SKYBLUE (-8715 4625);
DISPLAY INVISIBLE (-8715 4625);
FORCEPROP 2 LAST CDS_LIB pure_quanta
J 2
(-8675 4650);
DISPLAY INVISIBLE (-8675 4650);
FORCEPROP 1 LAST PATH I395
J 2
(-8725 4825);
DISPLAY 0.978723 (-8725 4825);
PAINT WHITE (-8725 4825);
DISPLAY INVISIBLE (-8725 4825);
FORCEPROP 1 LAST PART_NUMBER CS22202JB07
J 2
(-8715 4525);
DISPLAY 0.510638 (-8715 4525);
PAINT SKYBLUE (-8715 4525);
DISPLAY INVISIBLE (-8715 4525);
FORCEADD Q_RES..2
R 2
(-8675 4350);
FORCEPROP 1 LAST LOCATION R393
J 2
(-8725 4425);
DISPLAY 0.489362 (-8725 4425);
PAINT SKYBLUE (-8725 4425);
FORCEPROP 0 LAST $SEC 1
J 0
(-8725 4450);
DISPLAY 0.680851 (-8725 4450);
PAINT MONO (-8725 4450);
DISPLAY INVISIBLE (-8725 4450);
FORCEPROP 0 LAST CDS_SEC 1
J 0
(-8725 4450);
DISPLAY 0.680851 (-8725 4450);
DISPLAY INVISIBLE (-8725 4450);
FORCEPROP 1 LASTPIN (-8675 4450) $PN 1
J 2
(-8680 4412);
DISPLAY 0.489362 (-8680 4412);
PAINT MONO (-8680 4412);
FORCEPROP 1 LASTPIN (-8675 4250) $PN 2
J 2
(-8680 4260);
DISPLAY 0.489362 (-8680 4260);
PAINT MONO (-8680 4260);
FORCEPROP 1 LAST PACK_TYPE 0402LF
J 2
(-8725 4275);
DISPLAY 0.489362 (-8725 4275);
PAINT SKYBLUE (-8725 4275);
FORCEPROP 1 LAST VALUE 2.2K
J 2
(-8725 4375);
DISPLAY 0.489362 (-8725 4375);
PAINT SKYBLUE (-8725 4375);
FORCEPROP 1 LAST MATERIAL CHIP
J 2
(-8725 4325);
DISPLAY 0.489362 (-8725 4325);
PAINT SKYBLUE (-8725 4325);
FORCEPROP 1 LAST TOLERANCE 5%
J 2
(-8720 4375);
DISPLAY 0.510638 (-8720 4375);
PAINT SKYBLUE (-8720 4375);
DISPLAY INVISIBLE (-8720 4375);
FORCEPROP 1 LAST WATTAGE 1/16W
J 2
(-8715 4325);
DISPLAY 0.510638 (-8715 4325);
PAINT SKYBLUE (-8715 4325);
DISPLAY INVISIBLE (-8715 4325);
FORCEPROP 2 LAST CDS_LIB pure_quanta
J 0
(-8675 4350);
DISPLAY INVISIBLE (-8675 4350);
FORCEPROP 1 LAST PATH I396
J 2
(-8725 4525);
DISPLAY 0.978723 (-8725 4525);
PAINT WHITE (-8725 4525);
DISPLAY INVISIBLE (-8725 4525);
FORCEPROP 1 LAST PART_NUMBER CS22202JB07
J 2
(-8715 4225);
DISPLAY 0.510638 (-8715 4225);
PAINT SKYBLUE (-8715 4225);
DISPLAY INVISIBLE (-8715 4225);
FORCEADD Q_RES..2
(-8550 4350);
FORCEPROP 1 LAST LOCATION R394
J 0
(-8500 4425);
DISPLAY 0.489362 (-8500 4425);
PAINT SKYBLUE (-8500 4425);
FORCEPROP 0 LAST $SEC 1
J 0
(-8500 4450);
DISPLAY 0.680851 (-8500 4450);
PAINT MONO (-8500 4450);
DISPLAY INVISIBLE (-8500 4450);
FORCEPROP 0 LAST CDS_SEC 1
J 0
(-8500 4450);
DISPLAY 0.680851 (-8500 4450);
DISPLAY INVISIBLE (-8500 4450);
FORCEPROP 1 LASTPIN (-8550 4450) $PN 1
J 0
(-8545 4412);
DISPLAY 0.489362 (-8545 4412);
PAINT MONO (-8545 4412);
FORCEPROP 1 LASTPIN (-8550 4250) $PN 2
J 0
(-8545 4260);
DISPLAY 0.489362 (-8545 4260);
PAINT MONO (-8545 4260);
FORCEPROP 1 LAST PACK_TYPE 0402LF
J 0
(-8500 4275);
DISPLAY 0.489362 (-8500 4275);
PAINT SKYBLUE (-8500 4275);
FORCEPROP 1 LAST VALUE 2.2K
J 0
(-8500 4375);
DISPLAY 0.489362 (-8500 4375);
PAINT SKYBLUE (-8500 4375);
FORCEPROP 1 LAST MATERIAL CHIP
J 0
(-8500 4325);
DISPLAY 0.489362 (-8500 4325);
PAINT SKYBLUE (-8500 4325);
FORCEPROP 1 LAST TOLERANCE 5%
J 0
(-8505 4375);
DISPLAY 0.510638 (-8505 4375);
PAINT SKYBLUE (-8505 4375);
DISPLAY INVISIBLE (-8505 4375);
FORCEPROP 1 LAST WATTAGE 1/16W
J 0
(-8510 4325);
DISPLAY 0.510638 (-8510 4325);
PAINT SKYBLUE (-8510 4325);
DISPLAY INVISIBLE (-8510 4325);
FORCEPROP 2 LAST CDS_LIB pure_quanta
J 2
(-8550 4350);
DISPLAY INVISIBLE (-8550 4350);
FORCEPROP 1 LAST PATH I397
J 0
(-8500 4525);
DISPLAY 0.978723 (-8500 4525);
PAINT WHITE (-8500 4525);
DISPLAY INVISIBLE (-8500 4525);
FORCEPROP 1 LAST PART_NUMBER CS22202JB07
J 0
(-8510 4225);
DISPLAY 0.510638 (-8510 4225);
PAINT SKYBLUE (-8510 4225);
DISPLAY INVISIBLE (-8510 4225);
FORCEADD OFFPAGE..2
(-1975 4725);
FORCEPROP 2 LAST $XR1 82 
J 0
(-1696 4725);
DISPLAY 0.638298 (-1696 4725);
PAINT MONO (-1696 4725);
FORCEPROP 2 LAST $XR0 27 
J 0
(-1786 4725);
DISPLAY 0.638298 (-1786 4725);
PAINT MONO (-1786 4725);
FORCEPROP 2 LAST CDS_LIB standard
J 0
(-1975 4725);
DISPLAY INVISIBLE (-1975 4725);
FORCEPROP 1 LAST OFFPAGE TRUE
J 0
(-1650 4600);
DISPLAY 0.872340 (-1650 4600);
PAINT GREEN (-1650 4600);
DISPLAY INVISIBLE (-1650 4600);
FORCEPROP 1 LAST COMMENT_BODY TRUE
J 0
(-2020 4630);
DISPLAY 0.872340 (-2020 4630);
PAINT GREEN (-2020 4630);
DISPLAY INVISIBLE (-2020 4630);
FORCEPROP 2 LAST PATH I398
J 0
(-1800 4800);
DISPLAY 0.680851 (-1800 4800);
DISPLAY INVISIBLE (-1800 4800);
FORCEADD Q_RES..1
(-2725 4725);
FORCEPROP 1 LAST LOCATION R489
J 0
(-2625 4725);
DISPLAY 0.489362 (-2625 4725);
PAINT SKYBLUE (-2625 4725);
FORCEPROP 2 LAST $SEC 1
J 0
(-2775 4925);
DISPLAY 0.680851 (-2775 4925);
PAINT MONO (-2775 4925);
DISPLAY INVISIBLE (-2775 4925);
FORCEPROP 2 LAST CDS_SEC 1
J 0
(-2775 4925);
DISPLAY 0.680851 (-2775 4925);
DISPLAY INVISIBLE (-2775 4925);
FORCEPROP 1 LASTPIN (-2825 4725) $PN 1
J 0
(-2813 4737);
DISPLAY 0.489362 (-2813 4737);
PAINT MONO (-2813 4737);
FORCEPROP 1 LASTPIN (-2625 4725) $PN 2
J 0
(-2663 4737);
DISPLAY 0.489362 (-2663 4737);
PAINT MONO (-2663 4737);
FORCEPROP 1 LAST VALUE 33
J 2
(-2850 4725);
DISPLAY 0.489362 (-2850 4725);
PAINT SKYBLUE (-2850 4725);
FORCEPROP 1 LAST PACK_TYPE 0402LF
J 2
(-2550 4650);
DISPLAY 0.489362 (-2550 4650);
PAINT SKYBLUE (-2550 4650);
DISPLAY INVISIBLE (-2550 4650);
FORCEPROP 1 LAST TOLERANCE 5%
J 0
(-2850 4700);
DISPLAY 0.489362 (-2850 4700);
PAINT SKYBLUE (-2850 4700);
DISPLAY INVISIBLE (-2850 4700);
FORCEPROP 1 LAST MATERIAL CHIP
J 2
(-2550 4700);
DISPLAY 0.489362 (-2550 4700);
PAINT SKYBLUE (-2550 4700);
DISPLAY INVISIBLE (-2550 4700);
FORCEPROP 1 LAST WATTAGE 1/16W
J 2
(-2800 4650);
DISPLAY 0.489362 (-2800 4650);
PAINT SKYBLUE (-2800 4650);
DISPLAY INVISIBLE (-2800 4650);
FORCEPROP 2 LAST CDS_LIB pure_quanta
J 0
(-2725 4725);
DISPLAY INVISIBLE (-2725 4725);
FORCEPROP 2 LAST BOM_COST MEM
J 2
(-2700 4875);
DISPLAY 0.744681 (-2700 4875);
PAINT WHITE (-2700 4875);
DISPLAY INVISIBLE (-2700 4875);
FORCEPROP 1 LAST PATH I399
J 0
(-2775 4875);
DISPLAY 0.978723 (-2775 4875);
PAINT WHITE (-2775 4875);
DISPLAY INVISIBLE (-2775 4875);
FORCEPROP 1 LAST PART_NUMBER CS03302JB10
J 2
(-2625 4775);
DISPLAY 0.489362 (-2625 4775);
PAINT SKYBLUE (-2625 4775);
DISPLAY INVISIBLE (-2625 4775);
FORCEADD OFFPAGE..2
(-1975 4875);
FORCEPROP 2 LAST $XR0 81 
J 0
(-1786 4875);
DISPLAY 0.638298 (-1786 4875);
PAINT MONO (-1786 4875);
FORCEPROP 2 LAST CDS_LIB standard
J 2
(-1975 4875);
DISPLAY INVISIBLE (-1975 4875);
FORCEPROP 1 LAST OFFPAGE TRUE
J 0
(-1650 4750);
DISPLAY 0.872340 (-1650 4750);
PAINT GREEN (-1650 4750);
DISPLAY INVISIBLE (-1650 4750);
FORCEPROP 1 LAST COMMENT_BODY TRUE
J 0
(-2020 4780);
DISPLAY 0.872340 (-2020 4780);
PAINT GREEN (-2020 4780);
DISPLAY INVISIBLE (-2020 4780);
FORCEPROP 2 LAST PATH I400
J 0
(-1675 4925);
DISPLAY 0.680851 (-1675 4925);
DISPLAY INVISIBLE (-1675 4925);
FORCEADD Q_RES..1
(-2725 4875);
FORCEPROP 1 LAST LOCATION R247
J 0
(-2600 4875);
DISPLAY 0.489362 (-2600 4875);
PAINT SKYBLUE (-2600 4875);
FORCEPROP 0 LAST $SEC 1
J 2
(-2600 4925);
DISPLAY 0.680851 (-2600 4925);
PAINT MONO (-2600 4925);
DISPLAY INVISIBLE (-2600 4925);
FORCEPROP 0 LAST CDS_SEC 1
J 2
(-2600 4925);
DISPLAY 1.021277 (-2600 4925);
DISPLAY INVISIBLE (-2600 4925);
FORCEPROP 1 LASTPIN (-2825 4875) $PN 1
J 0
(-2813 4887);
DISPLAY 0.489362 (-2813 4887);
PAINT MONO (-2813 4887);
FORCEPROP 1 LASTPIN (-2625 4875) $PN 2
J 0
(-2663 4887);
DISPLAY 0.489362 (-2663 4887);
PAINT MONO (-2663 4887);
FORCEPROP 1 LAST VALUE 33
J 2
(-2850 4875);
DISPLAY 0.489362 (-2850 4875);
PAINT SKYBLUE (-2850 4875);
FORCEPROP 1 LAST PACK_TYPE 0402LF
J 2
(-2550 4800);
DISPLAY 0.489362 (-2550 4800);
PAINT SKYBLUE (-2550 4800);
DISPLAY INVISIBLE (-2550 4800);
FORCEPROP 1 LAST TOLERANCE 5%
J 0
(-2850 4850);
DISPLAY 0.489362 (-2850 4850);
PAINT SKYBLUE (-2850 4850);
DISPLAY INVISIBLE (-2850 4850);
FORCEPROP 1 LAST MATERIAL CHIP
J 2
(-2550 4850);
DISPLAY 0.489362 (-2550 4850);
PAINT SKYBLUE (-2550 4850);
DISPLAY INVISIBLE (-2550 4850);
FORCEPROP 1 LAST WATTAGE 1/16W
J 2
(-2800 4800);
DISPLAY 0.489362 (-2800 4800);
PAINT SKYBLUE (-2800 4800);
DISPLAY INVISIBLE (-2800 4800);
FORCEPROP 2 LAST BOM_COST MEM
J 2
(-2700 5025);
DISPLAY 0.744681 (-2700 5025);
PAINT WHITE (-2700 5025);
DISPLAY INVISIBLE (-2700 5025);
FORCEPROP 2 LAST CDS_LIB pure_quanta
J 2
(-2725 4875);
DISPLAY INVISIBLE (-2725 4875);
FORCEPROP 1 LAST PATH I401
J 0
(-2775 5025);
DISPLAY 0.978723 (-2775 5025);
PAINT WHITE (-2775 5025);
DISPLAY INVISIBLE (-2775 5025);
FORCEPROP 1 LAST PART_NUMBER CS03302JB10
J 2
(-2625 4925);
DISPLAY 0.489362 (-2625 4925);
PAINT SKYBLUE (-2625 4925);
DISPLAY INVISIBLE (-2625 4925);
FORCEADD TP..1
R 4
(-5900 1625);
FORCEPROP 1 LAST LOCATION TP10
J 1
(-5900 1525);
DISPLAY 0.489362 (-5900 1525);
PAINT SKYBLUE (-5900 1525);
FORCEPROP 0 LAST $SEC 1
J 0
(-5925 1600);
DISPLAY 0.680851 (-5925 1600);
PAINT MONO (-5925 1600);
DISPLAY INVISIBLE (-5925 1600);
FORCEPROP 0 LAST CDS_SEC 1
J 0
(-5925 1600);
DISPLAY 0.680851 (-5925 1600);
DISPLAY INVISIBLE (-5925 1600);
FORCEPROP 0 LASTPIN (-5900 1675) $PN 1
R 1
J 0
(-5910 1685);
DISPLAY 0.489362 (-5910 1685);
PAINT MONO (-5910 1685);
FORCEPROP 1 LAST MATERIAL NA
J 0
(-5925 1575);
DISPLAY 0.489362 (-5925 1575);
PAINT SKYBLUE (-5925 1575);
FORCEPROP 1 LAST PACK_TYPE TP
R 2
J 1
(-5955 1690);
DISPLAY 0.446809 (-5955 1690);
PAINT SKYBLUE (-5955 1690);
DISPLAY INVISIBLE (-5955 1690);
FORCEPROP 2 LAST CDS_LIB pure_quanta
J 0
(-5900 1625);
DISPLAY INVISIBLE (-5900 1625);
FORCEPROP 1 LASTPIN (-5900 1675) $PIN_NUMBER ?
R 2
J 2
(-5950 1675);
DISPLAY 0.702128 (-5950 1675);
PAINT MONO (-5950 1675);
DISPLAY INVISIBLE (-5950 1675);
FORCEPROP 1 LAST PATH I403
R 2
J 1
(-5905 1580);
DISPLAY 0.446809 (-5905 1580);
PAINT GREEN (-5905 1580);
DISPLAY INVISIBLE (-5905 1580);
FORCEPROP 1 LAST PART_NUMBER TP26
R 2
J 1
(-5955 1670);
DISPLAY 0.446809 (-5955 1670);
PAINT SKYBLUE (-5955 1670);
DISPLAY INVISIBLE (-5955 1670);
FORCEADD TP..1
R 4
(-6700 1625);
FORCEPROP 1 LAST LOCATION TP1
J 1
(-6700 1525);
DISPLAY 0.489362 (-6700 1525);
PAINT SKYBLUE (-6700 1525);
FORCEPROP 0 LAST $SEC 1
J 0
(-6725 1600);
DISPLAY 0.680851 (-6725 1600);
PAINT MONO (-6725 1600);
DISPLAY INVISIBLE (-6725 1600);
FORCEPROP 0 LAST CDS_SEC 1
J 0
(-6725 1600);
DISPLAY 0.680851 (-6725 1600);
DISPLAY INVISIBLE (-6725 1600);
FORCEPROP 0 LASTPIN (-6700 1675) $PN 1
R 1
J 0
(-6710 1685);
DISPLAY 0.489362 (-6710 1685);
PAINT MONO (-6710 1685);
FORCEPROP 1 LAST MATERIAL NA
J 0
(-6725 1575);
DISPLAY 0.489362 (-6725 1575);
PAINT SKYBLUE (-6725 1575);
FORCEPROP 1 LAST PACK_TYPE TP
R 2
J 1
(-6755 1690);
DISPLAY 0.446809 (-6755 1690);
PAINT SKYBLUE (-6755 1690);
DISPLAY INVISIBLE (-6755 1690);
FORCEPROP 1 LASTPIN (-6700 1675) $PIN_NUMBER ?
R 2
J 2
(-6750 1675);
DISPLAY 0.702128 (-6750 1675);
PAINT MONO (-6750 1675);
DISPLAY INVISIBLE (-6750 1675);
FORCEPROP 2 LAST CDS_LIB pure_quanta
R 2
J 0
(-6700 1625);
DISPLAY INVISIBLE (-6700 1625);
FORCEPROP 1 LAST PATH I404
R 2
J 1
(-6705 1580);
DISPLAY 0.446809 (-6705 1580);
PAINT GREEN (-6705 1580);
DISPLAY INVISIBLE (-6705 1580);
FORCEPROP 1 LAST PART_NUMBER TP26
R 2
J 1
(-6755 1670);
DISPLAY 0.446809 (-6755 1670);
PAINT SKYBLUE (-6755 1670);
DISPLAY INVISIBLE (-6755 1670);
FORCEADD OFFPAGE..2
(-425 3825);
FORCEPROP 2 LAST $XR1 82 
J 0
(-146 3825);
DISPLAY 0.638298 (-146 3825);
PAINT MONO (-146 3825);
FORCEPROP 2 LAST $XR0 54 
J 0
(-236 3825);
DISPLAY 0.638298 (-236 3825);
PAINT MONO (-236 3825);
FORCEPROP 2 LAST CDS_LIB standard
J 0
(-425 3825);
DISPLAY INVISIBLE (-425 3825);
FORCEPROP 1 LAST OFFPAGE TRUE
J 0
(-100 3700);
DISPLAY 0.872340 (-100 3700);
PAINT GREEN (-100 3700);
DISPLAY INVISIBLE (-100 3700);
FORCEPROP 1 LAST COMMENT_BODY TRUE
J 0
(-470 3730);
DISPLAY 0.872340 (-470 3730);
PAINT GREEN (-470 3730);
DISPLAY INVISIBLE (-470 3730);
FORCEPROP 2 LAST PATH I405
J 0
(-250 3900);
DISPLAY 0.680851 (-250 3900);
DISPLAY INVISIBLE (-250 3900);
FORCEADD OFFPAGE..4
R 2
(-1700 3825);
FORCEPROP 2 LAST $XR1 82 
J 0
(-2011 3825);
DISPLAY 0.638298 (-2011 3825);
PAINT MONO (-2011 3825);
FORCEPROP 2 LAST $XR0 27 
J 0
(-1921 3825);
DISPLAY 0.638298 (-1921 3825);
PAINT MONO (-1921 3825);
FORCEPROP 2 LAST CDS_LIB standard
J 0
(-1700 3825);
DISPLAY INVISIBLE (-1700 3825);
FORCEPROP 1 LAST OFFPAGE TRUE
J 2
(-2025 3700);
DISPLAY 0.872340 (-2025 3700);
PAINT GREEN (-2025 3700);
DISPLAY INVISIBLE (-2025 3700);
FORCEPROP 1 LAST COMMENT_BODY TRUE
J 2
(-1675 3725);
DISPLAY 0.872340 (-1675 3725);
PAINT GREEN (-1675 3725);
DISPLAY INVISIBLE (-1675 3725);
FORCEPROP 2 LAST PATH I406
J 0
(-1650 3900);
DISPLAY 0.680851 (-1650 3900);
DISPLAY INVISIBLE (-1650 3900);
FORCEADD UNIVERSAL_POWER..1
(-5650 1575);
FORCEPROP 3 LASTPIN (-5650 1525) SIG_NAME P1V5_BAT\g
J 0
(-5640 1535);
DISPLAY 0.659574 (-5640 1535);
PAINT MONO (-5640 1535);
DISPLAY INVISIBLE (-5640 1535);
FORCEPROP 1 LAST HDL_POWER P1V5_BAT
J 1
(-5650 1625);
DISPLAY 0.489362 (-5650 1625);
PAINT GREEN (-5650 1625);
FORCEPROP 2 LAST CDS_LIB pure_quanta_power
J 0
(-5650 1575);
DISPLAY INVISIBLE (-5650 1575);
FORCEPROP 1 LAST PATH I408
J 0
(-5600 1600);
DISPLAY 0.872340 (-5600 1600);
PAINT AQUA (-5600 1600);
DISPLAY INVISIBLE (-5600 1600);
FORCEADD UNIVERSAL_GND..1
(-5650 625);
FORCEPROP 3 LASTPIN (-5650 675) SIG_NAME GND\g
J 0
(-5640 685);
DISPLAY 0.659574 (-5640 685);
PAINT MONO (-5640 685);
DISPLAY INVISIBLE (-5640 685);
FORCEPROP 2 LAST CDS_LIB pure_quanta_power
J 0
(-5650 625);
DISPLAY INVISIBLE (-5650 625);
FORCEPROP 1 LAST HDL_POWER GND
J 1
(-5625 550);
DISPLAY 0.872340 (-5625 550);
PAINT GREEN (-5625 550);
DISPLAY INVISIBLE (-5625 550);
FORCEPROP 1 LAST PATH I410
J 0
(-5575 625);
DISPLAY 0.872340 (-5575 625);
PAINT AQUA (-5575 625);
DISPLAY INVISIBLE (-5575 625);
FORCEADD OFFPAGE..3
R 2
(-2275 950);
FORCEPROP 2 LAST $XR1 82 
J 0
(-2614 950);
DISPLAY 0.638298 (-2614 950);
PAINT MONO (-2614 950);
FORCEPROP 2 LAST $XR0 27 
J 0
(-2524 950);
DISPLAY 0.638298 (-2524 950);
PAINT MONO (-2524 950);
FORCEPROP 2 LAST CDS_LIB standard
J 0
(-2275 950);
DISPLAY INVISIBLE (-2275 950);
FORCEPROP 1 LAST OFFPAGE TRUE
J 2
(-2600 825);
DISPLAY 0.872340 (-2600 825);
DISPLAY INVISIBLE (-2600 825);
FORCEPROP 1 LAST COMMENT_BODY TRUE
J 2
(-2225 850);
DISPLAY 0.872340 (-2225 850);
PAINT GREEN (-2225 850);
DISPLAY INVISIBLE (-2225 850);
FORCEPROP 2 LAST PATH I415
J 0
(-2525 1000);
DISPLAY 0.680851 (-2525 1000);
DISPLAY INVISIBLE (-2525 1000);
FORCEADD OFFPAGE..3
R 2
(-2275 850);
FORCEPROP 2 LAST $XR2 172 
J 0
(-2734 850);
DISPLAY 0.638298 (-2734 850);
PAINT MONO (-2734 850);
FORCEPROP 2 LAST $XR1 82 
J 0
(-2614 850);
DISPLAY 0.638298 (-2614 850);
PAINT MONO (-2614 850);
FORCEPROP 2 LAST $XR0 27 
J 0
(-2524 850);
DISPLAY 0.638298 (-2524 850);
PAINT MONO (-2524 850);
FORCEPROP 2 LAST CDS_LIB standard
J 0
(-2275 850);
DISPLAY INVISIBLE (-2275 850);
FORCEPROP 1 LAST OFFPAGE TRUE
J 2
(-2600 725);
DISPLAY 0.872340 (-2600 725);
DISPLAY INVISIBLE (-2600 725);
FORCEPROP 1 LAST COMMENT_BODY TRUE
J 2
(-2225 750);
DISPLAY 0.872340 (-2225 750);
PAINT GREEN (-2225 750);
DISPLAY INVISIBLE (-2225 750);
FORCEPROP 2 LAST PATH I416
J 0
(-2225 925);
DISPLAY 0.680851 (-2225 925);
DISPLAY INVISIBLE (-2225 925);
FORCEADD OFFPAGE..3
R 2
(-2275 750);
FORCEPROP 2 LAST $XR2 172 
J 0
(-2734 750);
DISPLAY 0.638298 (-2734 750);
PAINT MONO (-2734 750);
FORCEPROP 2 LAST $XR1 82 
J 0
(-2614 750);
DISPLAY 0.638298 (-2614 750);
PAINT MONO (-2614 750);
FORCEPROP 2 LAST $XR0 27 
J 0
(-2524 750);
DISPLAY 0.638298 (-2524 750);
PAINT MONO (-2524 750);
FORCEPROP 2 LAST CDS_LIB standard
J 0
(-2275 750);
DISPLAY INVISIBLE (-2275 750);
FORCEPROP 1 LAST OFFPAGE TRUE
J 2
(-2600 625);
DISPLAY 0.872340 (-2600 625);
DISPLAY INVISIBLE (-2600 625);
FORCEPROP 1 LAST COMMENT_BODY TRUE
J 2
(-2225 650);
DISPLAY 0.872340 (-2225 650);
PAINT GREEN (-2225 650);
DISPLAY INVISIBLE (-2225 650);
FORCEPROP 2 LAST PATH I417
J 0
(-2225 825);
DISPLAY 0.680851 (-2225 825);
DISPLAY INVISIBLE (-2225 825);
FORCEADD OFFPAGE..3
R 2
(-2275 650);
FORCEPROP 2 LAST $XR2 172 
J 0
(-2734 650);
DISPLAY 0.638298 (-2734 650);
PAINT MONO (-2734 650);
FORCEPROP 2 LAST $XR1 82 
J 0
(-2614 650);
DISPLAY 0.638298 (-2614 650);
PAINT MONO (-2614 650);
FORCEPROP 2 LAST $XR0 27 
J 0
(-2524 650);
DISPLAY 0.638298 (-2524 650);
PAINT MONO (-2524 650);
FORCEPROP 2 LAST CDS_LIB standard
J 0
(-2275 650);
DISPLAY INVISIBLE (-2275 650);
FORCEPROP 1 LAST OFFPAGE TRUE
J 2
(-2600 525);
DISPLAY 0.872340 (-2600 525);
DISPLAY INVISIBLE (-2600 525);
FORCEPROP 1 LAST COMMENT_BODY TRUE
J 2
(-2225 550);
DISPLAY 0.872340 (-2225 550);
PAINT GREEN (-2225 550);
DISPLAY INVISIBLE (-2225 550);
FORCEPROP 2 LAST PATH I418
J 0
(-2225 725);
DISPLAY 0.680851 (-2225 725);
DISPLAY INVISIBLE (-2225 725);
FORCEADD OFFPAGE..3
(-675 950);
FORCEPROP 2 LAST $XR1 82 
J 0
(-371 950);
DISPLAY 0.638298 (-371 950);
PAINT MONO (-371 950);
FORCEPROP 2 LAST $XR0 54 
J 0
(-461 950);
DISPLAY 0.638298 (-461 950);
PAINT MONO (-461 950);
FORCEPROP 2 LAST CDS_LIB standard
J 2
(-675 950);
DISPLAY INVISIBLE (-675 950);
FORCEPROP 1 LAST OFFPAGE TRUE
J 0
(-350 825);
DISPLAY 0.872340 (-350 825);
DISPLAY INVISIBLE (-350 825);
FORCEPROP 1 LAST COMMENT_BODY TRUE
J 0
(-725 850);
DISPLAY 0.872340 (-725 850);
PAINT GREEN (-725 850);
DISPLAY INVISIBLE (-725 850);
FORCEPROP 2 LAST PATH I419
J 2
(-725 1025);
DISPLAY 0.680851 (-725 1025);
DISPLAY INVISIBLE (-725 1025);
FORCEADD OFFPAGE..3
(-675 850);
FORCEPROP 2 LAST $XR1 82 
J 0
(-371 850);
DISPLAY 0.638298 (-371 850);
PAINT MONO (-371 850);
FORCEPROP 2 LAST $XR0 54 
J 0
(-461 850);
DISPLAY 0.638298 (-461 850);
PAINT MONO (-461 850);
FORCEPROP 2 LAST CDS_LIB standard
J 0
(-675 850);
DISPLAY INVISIBLE (-675 850);
FORCEPROP 1 LAST OFFPAGE TRUE
J 0
(-350 725);
DISPLAY 0.872340 (-350 725);
DISPLAY INVISIBLE (-350 725);
FORCEPROP 1 LAST COMMENT_BODY TRUE
J 0
(-725 750);
DISPLAY 0.872340 (-725 750);
PAINT GREEN (-725 750);
DISPLAY INVISIBLE (-725 750);
FORCEPROP 2 LAST PATH I420
J 0
(-475 925);
DISPLAY 0.680851 (-475 925);
DISPLAY INVISIBLE (-475 925);
FORCEADD OFFPAGE..3
(-675 750);
FORCEPROP 2 LAST $XR1 82 
J 0
(-371 750);
DISPLAY 0.638298 (-371 750);
PAINT MONO (-371 750);
FORCEPROP 2 LAST $XR0 54 
J 0
(-461 750);
DISPLAY 0.638298 (-461 750);
PAINT MONO (-461 750);
FORCEPROP 2 LAST CDS_LIB standard
J 0
(-675 750);
DISPLAY INVISIBLE (-675 750);
FORCEPROP 1 LAST OFFPAGE TRUE
J 0
(-350 625);
DISPLAY 0.872340 (-350 625);
DISPLAY INVISIBLE (-350 625);
FORCEPROP 1 LAST COMMENT_BODY TRUE
J 0
(-725 650);
DISPLAY 0.872340 (-725 650);
PAINT GREEN (-725 650);
DISPLAY INVISIBLE (-725 650);
FORCEPROP 2 LAST PATH I421
J 0
(-475 825);
DISPLAY 0.680851 (-475 825);
DISPLAY INVISIBLE (-475 825);
FORCEADD OFFPAGE..3
(-675 650);
FORCEPROP 2 LAST $XR1 82 
J 0
(-371 650);
DISPLAY 0.638298 (-371 650);
PAINT MONO (-371 650);
FORCEPROP 2 LAST $XR0 54 
J 0
(-461 650);
DISPLAY 0.638298 (-461 650);
PAINT MONO (-461 650);
FORCEPROP 2 LAST CDS_LIB standard
J 0
(-675 650);
DISPLAY INVISIBLE (-675 650);
FORCEPROP 1 LAST OFFPAGE TRUE
J 0
(-350 525);
DISPLAY 0.872340 (-350 525);
DISPLAY INVISIBLE (-350 525);
FORCEPROP 1 LAST COMMENT_BODY TRUE
J 0
(-725 550);
DISPLAY 0.872340 (-725 550);
PAINT GREEN (-725 550);
DISPLAY INVISIBLE (-725 550);
FORCEPROP 2 LAST PATH I422
J 0
(-475 725);
DISPLAY 0.680851 (-475 725);
DISPLAY INVISIBLE (-475 725);
FORCEADD CONN10_HBC1051L300D8H..1
(-1475 750);
FORCEPROP 1 LAST LOCATION J212
J 0
(-1594 1106);
DISPLAY 0.723404 (-1594 1106);
PAINT GREEN (-1594 1106);
FORCEPROP 2 LAST SEC 1
J 0
(-1575 1325);
DISPLAY 0.680851 (-1575 1325);
PAINT MONO (-1575 1325);
DISPLAY INVISIBLE (-1575 1325);
FORCEPROP 2 LASTPIN (-1750 950) $PN 1
J 2
(-1760 960);
DISPLAY 0.680851 (-1760 960);
PAINT MONO (-1760 960);
FORCEPROP 2 LASTPIN (-1200 950) $PN 2
J 0
(-1190 960);
DISPLAY 0.680851 (-1190 960);
PAINT MONO (-1190 960);
FORCEPROP 2 LASTPIN (-1750 850) $PN 3
J 2
(-1760 860);
DISPLAY 0.680851 (-1760 860);
PAINT MONO (-1760 860);
FORCEPROP 2 LASTPIN (-1200 850) $PN 4
J 0
(-1190 860);
DISPLAY 0.680851 (-1190 860);
PAINT MONO (-1190 860);
FORCEPROP 2 LASTPIN (-1750 750) $PN 5
J 2
(-1760 760);
DISPLAY 0.680851 (-1760 760);
PAINT MONO (-1760 760);
FORCEPROP 2 LASTPIN (-1200 750) $PN 6
J 0
(-1190 760);
DISPLAY 0.680851 (-1190 760);
PAINT MONO (-1190 760);
FORCEPROP 2 LASTPIN (-1750 650) $PN 7
J 2
(-1760 660);
DISPLAY 0.680851 (-1760 660);
PAINT MONO (-1760 660);
FORCEPROP 2 LASTPIN (-1200 650) $PN 8
J 0
(-1190 660);
DISPLAY 0.680851 (-1190 660);
PAINT MONO (-1190 660);
FORCEPROP 2 LASTPIN (-1750 550) $PN 9
J 2
(-1760 560);
DISPLAY 0.680851 (-1760 560);
PAINT MONO (-1760 560);
FORCEPROP 2 LASTPIN (-1200 550) $PN 10
J 0
(-1190 560);
DISPLAY 0.680851 (-1190 560);
PAINT MONO (-1190 560);
FORCEPROP 1 LAST MATERIAL IO
J 0
(-1594 1007);
DISPLAY 0.723404 (-1594 1007);
PAINT GREEN (-1594 1007);
FORCEPROP 2 LAST PART_TYPE THLF
J 0
(-1575 1200);
DISPLAY 0.680851 (-1575 1200);
FORCEPROP 2 LAST VALUE CONN10_HBC1051-L300D-8H
J 0
(-1575 1150);
DISPLAY 0.680851 (-1575 1150);
FORCEPROP 2 LAST CDS_LIB pure_quanta
J 0
(-1475 750);
DISPLAY INVISIBLE (-1475 750);
FORCEPROP 1 LAST NEEDS_NO_SIZE TRUE
J 0
(-1475 750);
DISPLAY 0.723404 (-1475 750);
PAINT GREEN (-1475 750);
DISPLAY INVISIBLE (-1475 750);
FORCEPROP 1 LAST CDS_LMAN_SYM_OUTLINE -125,250,125,-250
J 0
(-1475 750);
DISPLAY 0.468085 (-1475 750);
PAINT GREEN (-1475 750);
DISPLAY INVISIBLE (-1475 750);
FORCEPROP 2 LAST SEC_TYPE 
J 0
(-1575 1325);
DISPLAY 0.680851 (-1575 1325);
DISPLAY INVISIBLE (-1575 1325);
FORCEPROP 1 LAST PATH I423
J 0
(-1475 750);
DISPLAY 0.723404 (-1475 750);
PAINT GREEN (-1475 750);
DISPLAY INVISIBLE (-1475 750);
FORCEPROP 1 LAST PART_NUMBER DFHD10MS117
J 0
(-1594 1059);
DISPLAY 0.723404 (-1594 1059);
PAINT GREEN (-1594 1059);
DISPLAY INVISIBLE (-1594 1059);
FORCEADD SCONN8_G802M0083150RD3HR..1
(-500 2250);
FORCEPROP 1 LAST LOCATION J48
J 0
(-625 2475);
DISPLAY 0.723404 (-625 2475);
PAINT GREEN (-625 2475);
FORCEPROP 2 LAST SEC 1
J 0
(-600 2800);
DISPLAY 0.680851 (-600 2800);
PAINT MONO (-600 2800);
DISPLAY INVISIBLE (-600 2800);
FORCEPROP 2 LASTPIN (-775 2325) $PN 1
J 2
(-785 2335);
DISPLAY 0.680851 (-785 2335);
PAINT MONO (-785 2335);
FORCEPROP 2 LASTPIN (-225 2325) $PN 2
J 0
(-215 2335);
DISPLAY 0.680851 (-215 2335);
PAINT MONO (-215 2335);
FORCEPROP 2 LASTPIN (-775 2275) $PN 3
J 2
(-785 2285);
DISPLAY 0.680851 (-785 2285);
PAINT MONO (-785 2285);
FORCEPROP 2 LASTPIN (-225 2275) $PN 4
J 0
(-215 2285);
DISPLAY 0.680851 (-215 2285);
PAINT MONO (-215 2285);
FORCEPROP 2 LASTPIN (-775 2225) $PN 5
J 2
(-785 2235);
DISPLAY 0.680851 (-785 2235);
PAINT MONO (-785 2235);
FORCEPROP 2 LASTPIN (-225 2225) $PN 6
J 0
(-215 2235);
DISPLAY 0.680851 (-215 2235);
PAINT MONO (-215 2235);
FORCEPROP 2 LASTPIN (-775 2175) $PN 7
J 2
(-785 2185);
DISPLAY 0.680851 (-785 2185);
PAINT MONO (-785 2185);
FORCEPROP 2 LASTPIN (-225 2175) $PN 8
J 0
(-215 2185);
DISPLAY 0.680851 (-215 2185);
PAINT MONO (-215 2185);
FORCEPROP 2 LAST VALUE SCONN8_G802M0083150RD3HR
J 0
(-800 2525);
DISPLAY 0.680851 (-800 2525);
FORCEPROP 2 LAST PART_TYPE SMLF
J 0
(-625 2575);
DISPLAY 0.680851 (-625 2575);
FORCEPROP 1 LAST MATERIAL IO
J 0
(-619 2382);
DISPLAY 0.723404 (-619 2382);
PAINT GREEN (-619 2382);
FORCEPROP 1 LAST CDS_LMAN_SYM_OUTLINE -125,125,125,-125
J 0
(-500 2250);
DISPLAY 0.468085 (-500 2250);
PAINT GREEN (-500 2250);
DISPLAY INVISIBLE (-500 2250);
FORCEPROP 1 LAST NEEDS_NO_SIZE TRUE
J 0
(-500 2250);
DISPLAY 0.723404 (-500 2250);
PAINT GREEN (-500 2250);
DISPLAY INVISIBLE (-500 2250);
FORCEPROP 2 LAST CDS_LIB pure_quanta
J 0
(-500 2250);
DISPLAY INVISIBLE (-500 2250);
FORCEPROP 2 LAST SEC_TYPE 
J 0
(-600 2800);
DISPLAY 0.680851 (-600 2800);
DISPLAY INVISIBLE (-600 2800);
FORCEPROP 1 LAST PATH I424
J 0
(-500 2250);
DISPLAY 0.723404 (-500 2250);
PAINT GREEN (-500 2250);
DISPLAY INVISIBLE (-500 2250);
FORCEPROP 1 LAST PART_NUMBER DFHD08MS385
J 0
(-625 2425);
DISPLAY 0.723404 (-625 2425);
PAINT GREEN (-625 2425);
DISPLAY INVISIBLE (-625 2425);
FORCEADD SCONN8_G802M0083150RD3HR..1
(-500 2875);
FORCEPROP 1 LAST LOCATION J5
J 0
(-625 3100);
DISPLAY 0.723404 (-625 3100);
PAINT GREEN (-625 3100);
FORCEPROP 2 LAST SEC 1
J 0
(-600 3425);
DISPLAY 0.680851 (-600 3425);
PAINT MONO (-600 3425);
DISPLAY INVISIBLE (-600 3425);
FORCEPROP 2 LASTPIN (-775 2950) $PN 1
J 2
(-785 2960);
DISPLAY 0.680851 (-785 2960);
PAINT MONO (-785 2960);
FORCEPROP 2 LASTPIN (-225 2950) $PN 2
J 0
(-215 2960);
DISPLAY 0.680851 (-215 2960);
PAINT MONO (-215 2960);
FORCEPROP 2 LASTPIN (-775 2900) $PN 3
J 2
(-785 2910);
DISPLAY 0.680851 (-785 2910);
PAINT MONO (-785 2910);
FORCEPROP 2 LASTPIN (-225 2900) $PN 4
J 0
(-215 2910);
DISPLAY 0.680851 (-215 2910);
PAINT MONO (-215 2910);
FORCEPROP 2 LASTPIN (-775 2850) $PN 5
J 2
(-785 2860);
DISPLAY 0.680851 (-785 2860);
PAINT MONO (-785 2860);
FORCEPROP 2 LASTPIN (-225 2850) $PN 6
J 0
(-215 2860);
DISPLAY 0.680851 (-215 2860);
PAINT MONO (-215 2860);
FORCEPROP 2 LASTPIN (-775 2800) $PN 7
J 2
(-785 2810);
DISPLAY 0.680851 (-785 2810);
PAINT MONO (-785 2810);
FORCEPROP 2 LASTPIN (-225 2800) $PN 8
J 0
(-215 2810);
DISPLAY 0.680851 (-215 2810);
PAINT MONO (-215 2810);
FORCEPROP 2 LAST VALUE SCONN8_G802M0083150RD3HR
J 0
(-800 3150);
DISPLAY 0.680851 (-800 3150);
FORCEPROP 1 LAST MATERIAL IO
J 0
(-619 3007);
DISPLAY 0.723404 (-619 3007);
PAINT GREEN (-619 3007);
FORCEPROP 2 LAST PART_TYPE SMLF
J 0
(-625 3200);
DISPLAY 0.680851 (-625 3200);
FORCEPROP 1 LAST CDS_LMAN_SYM_OUTLINE -125,125,125,-125
J 0
(-500 2875);
DISPLAY 0.468085 (-500 2875);
PAINT GREEN (-500 2875);
DISPLAY INVISIBLE (-500 2875);
FORCEPROP 1 LAST NEEDS_NO_SIZE TRUE
J 0
(-500 2875);
DISPLAY 0.723404 (-500 2875);
PAINT GREEN (-500 2875);
DISPLAY INVISIBLE (-500 2875);
FORCEPROP 2 LAST CDS_LIB pure_quanta
J 0
(-500 2875);
DISPLAY INVISIBLE (-500 2875);
FORCEPROP 2 LAST SEC_TYPE 
J 0
(-600 3425);
DISPLAY 0.680851 (-600 3425);
DISPLAY INVISIBLE (-600 3425);
FORCEPROP 1 LAST PATH I425
J 0
(-500 2875);
DISPLAY 0.723404 (-500 2875);
PAINT GREEN (-500 2875);
DISPLAY INVISIBLE (-500 2875);
FORCEPROP 1 LAST PART_NUMBER DFHD08MS385
J 0
(-625 3050);
DISPLAY 0.723404 (-625 3050);
PAINT GREEN (-625 3050);
DISPLAY INVISIBLE (-625 3050);
FORCEADD Q_RES..2
(-5650 1350);
FORCEPROP 1 LAST LOCATION R5055
J 0
(-5605 1475);
DISPLAY 0.489362 (-5605 1475);
PAINT SKYBLUE (-5605 1475);
FORCEPROP 0 LAST $SEC 1
J 0
(-5600 1500);
DISPLAY 0.680851 (-5600 1500);
PAINT MONO (-5600 1500);
DISPLAY INVISIBLE (-5600 1500);
FORCEPROP 0 LAST CDS_SEC 1
J 0
(-5600 1500);
DISPLAY 0.680851 (-5600 1500);
DISPLAY INVISIBLE (-5600 1500);
FORCEPROP 1 LASTPIN (-5650 1450) $PN 1
J 0
(-5645 1412);
DISPLAY 0.787234 (-5645 1412);
PAINT MONO (-5645 1412);
FORCEPROP 1 LASTPIN (-5650 1250) $PN 2
J 0
(-5645 1260);
DISPLAY 0.787234 (-5645 1260);
PAINT MONO (-5645 1260);
FORCEPROP 1 LAST VALUE 10K
J 0
(-5625 1425);
DISPLAY 0.489362 (-5625 1425);
PAINT SKYBLUE (-5625 1425);
FORCEPROP 1 LAST PACK_TYPE 0402LF
J 0
(-5625 1225);
DISPLAY 0.489362 (-5625 1225);
PAINT SKYBLUE (-5625 1225);
FORCEPROP 1 LAST TOLERANCE 5%
J 0
(-5625 1375);
DISPLAY 0.489362 (-5625 1375);
PAINT SKYBLUE (-5625 1375);
FORCEPROP 1 LAST MATERIAL CHIP
J 0
(-5625 1275);
DISPLAY 0.489362 (-5625 1275);
PAINT SKYBLUE (-5625 1275);
FORCEPROP 1 LAST WATTAGE 1/16W
J 0
(-5625 1325);
DISPLAY 0.489362 (-5625 1325);
PAINT SKYBLUE (-5625 1325);
FORCEPROP 2 LAST CDS_LIB pure_quanta
J 0
(-5650 1350);
DISPLAY INVISIBLE (-5650 1350);
FORCEPROP 2 LAST BOM_COST I/O CONNECTOR
J 0
(-5625 1475);
DISPLAY 0.680851 (-5625 1475);
DISPLAY INVISIBLE (-5625 1475);
FORCEPROP 1 LAST PATH I427
J 0
(-5600 1525);
DISPLAY 0.978723 (-5600 1525);
PAINT WHITE (-5600 1525);
DISPLAY INVISIBLE (-5600 1525);
FORCEPROP 1 LAST PART_NUMBER CS31002JB08
J 0
(-5635 1300);
DISPLAY 0.638298 (-5635 1300);
PAINT SKYBLUE (-5635 1300);
DISPLAY INVISIBLE (-5635 1300);
FORCEADD Q_RES..2
(-5650 900);
FORCEPROP 1 LAST LOCATION R5056
J 0
(-5605 1025);
DISPLAY 0.489362 (-5605 1025);
PAINT SKYBLUE (-5605 1025);
FORCEPROP 0 LAST $SEC 1
J 0
(-5600 1050);
DISPLAY 0.680851 (-5600 1050);
PAINT MONO (-5600 1050);
DISPLAY INVISIBLE (-5600 1050);
FORCEPROP 0 LAST CDS_SEC 1
J 0
(-5600 1050);
DISPLAY 0.680851 (-5600 1050);
DISPLAY INVISIBLE (-5600 1050);
FORCEPROP 1 LASTPIN (-5650 1000) $PN 1
J 0
(-5645 962);
DISPLAY 0.787234 (-5645 962);
PAINT MONO (-5645 962);
FORCEPROP 1 LASTPIN (-5650 800) $PN 2
J 0
(-5645 810);
DISPLAY 0.787234 (-5645 810);
PAINT MONO (-5645 810);
FORCEPROP 1 LAST PACK_TYPE 0402LF
J 0
(-5625 775);
DISPLAY 0.489362 (-5625 775);
PAINT SKYBLUE (-5625 775);
FORCEPROP 1 LAST TOLERANCE 5%
J 0
(-5625 925);
DISPLAY 0.489362 (-5625 925);
PAINT SKYBLUE (-5625 925);
FORCEPROP 1 LAST MATERIAL EMPTY
J 0
(-5625 825);
DISPLAY 0.489362 (-5625 825);
PAINT SKYBLUE (-5625 825);
FORCEPROP 1 LAST VALUE 10K
J 0
(-5625 975);
DISPLAY 0.489362 (-5625 975);
PAINT SKYBLUE (-5625 975);
FORCEPROP 1 LAST WATTAGE 1/16W
J 0
(-5625 875);
DISPLAY 0.489362 (-5625 875);
PAINT SKYBLUE (-5625 875);
FORCEPROP 2 LAST BOM_COST I/O CONNECTOR
J 0
(-5625 1025);
DISPLAY 0.680851 (-5625 1025);
DISPLAY INVISIBLE (-5625 1025);
FORCEPROP 2 LAST CDS_LIB pure_quanta
J 0
(-5650 900);
DISPLAY INVISIBLE (-5650 900);
FORCEPROP 1 LAST PATH I428
J 0
(-5600 1075);
DISPLAY 0.978723 (-5600 1075);
PAINT WHITE (-5600 1075);
DISPLAY INVISIBLE (-5600 1075);
FORCEPROP 1 LAST PART_NUMBER CS31002JB08
J 0
(-5635 850);
DISPLAY 0.638298 (-5635 850);
PAINT SKYBLUE (-5635 850);
DISPLAY INVISIBLE (-5635 850);
FORCEADD Q_RES..1
(-1075 3825);
FORCEPROP 1 LAST LOCATION R1533
J 0
(-950 3825);
DISPLAY 0.638298 (-950 3825);
FORCEPROP 0 LAST $SEC 1
J 0
(-1125 3950);
DISPLAY 0.680851 (-1125 3950);
PAINT MONO (-1125 3950);
DISPLAY INVISIBLE (-1125 3950);
FORCEPROP 0 LAST CDS_SEC 1
J 0
(-1125 3950);
DISPLAY 0.680851 (-1125 3950);
DISPLAY INVISIBLE (-1125 3950);
FORCEPROP 1 LASTPIN (-1175 3825) $PN 1
J 0
(-1163 3837);
DISPLAY 0.787234 (-1163 3837);
PAINT MONO (-1163 3837);
FORCEPROP 1 LASTPIN (-975 3825) $PN 2
J 0
(-1013 3837);
DISPLAY 0.787234 (-1013 3837);
PAINT MONO (-1013 3837);
FORCEPROP 1 LAST TOLERANCE 5%
J 0
(-1075 3725);
DISPLAY 0.638298 (-1075 3725);
FORCEPROP 1 LAST VALUE 0
J 2
(-1175 3850);
DISPLAY 0.638298 (-1175 3850);
FORCEPROP 1 LAST WATTAGE 1/16W
J 2
(-1100 3725);
DISPLAY 0.638298 (-1100 3725);
FORCEPROP 1 LAST PACK_TYPE 0402LF
J 0
(-1000 3725);
DISPLAY 0.638298 (-1000 3725);
FORCEPROP 1 LAST MATERIAL CHIP
J 0
(-1125 3900);
DISPLAY 0.638298 (-1125 3900);
FORCEPROP 2 LAST CDS_LIB pure_quanta
J 0
(-1075 3825);
DISPLAY INVISIBLE (-1075 3825);
FORCEPROP 1 LAST PATH I429
J 0
(-1125 3975);
DISPLAY 0.978723 (-1125 3975);
PAINT WHITE (-1125 3975);
DISPLAY INVISIBLE (-1125 3975);
FORCEPROP 1 LAST PART_NUMBER CS00002JB13
J 0
(-1250 3775);
DISPLAY 0.638298 (-1250 3775);
DISPLAY INVISIBLE (-1250 3775);
FORCEADD OFFPAGE..4
R 2
(-5750 5425);
FORCEPROP 2 LAST $XR0 193 
J 0
(-6002 5425);
DISPLAY 0.638298 (-6002 5425);
PAINT MONO (-6002 5425);
FORCEPROP 2 LAST CDS_LIB standard
J 0
(-5750 5425);
DISPLAY INVISIBLE (-5750 5425);
FORCEPROP 1 LAST OFFPAGE TRUE
J 2
(-6075 5300);
DISPLAY 0.872340 (-6075 5300);
PAINT GREEN (-6075 5300);
DISPLAY INVISIBLE (-6075 5300);
FORCEPROP 1 LAST COMMENT_BODY TRUE
J 2
(-5725 5325);
DISPLAY 0.872340 (-5725 5325);
PAINT GREEN (-5725 5325);
DISPLAY INVISIBLE (-5725 5325);
FORCEPROP 2 LAST PATH I43
J 0
(-5700 5500);
DISPLAY 1.021277 (-5700 5500);
DISPLAY INVISIBLE (-5700 5500);
FORCEADD OFFPAGE..4
R 2
(-5750 5225);
FORCEPROP 2 LAST $XR0 200 
J 0
(-6002 5225);
DISPLAY 0.638298 (-6002 5225);
PAINT MONO (-6002 5225);
FORCEPROP 2 LAST CDS_LIB standard
J 0
(-5750 5225);
DISPLAY INVISIBLE (-5750 5225);
FORCEPROP 1 LAST OFFPAGE TRUE
J 2
(-6075 5100);
DISPLAY 0.872340 (-6075 5100);
PAINT GREEN (-6075 5100);
DISPLAY INVISIBLE (-6075 5100);
FORCEPROP 1 LAST COMMENT_BODY TRUE
J 2
(-5725 5125);
DISPLAY 0.872340 (-5725 5125);
PAINT GREEN (-5725 5125);
DISPLAY INVISIBLE (-5725 5125);
FORCEPROP 2 LAST PATH I46
J 0
(-5700 5300);
DISPLAY 1.021277 (-5700 5300);
DISPLAY INVISIBLE (-5700 5300);
FORCEADD OFFPAGE..2
R 2
(-6825 1975);
FORCEPROP 2 LAST $XR0 193 
J 0
(-7110 1975);
DISPLAY 0.638298 (-7110 1975);
PAINT MONO (-7110 1975);
FORCEPROP 2 LAST CDS_LIB standard
J 0
(-6825 1975);
DISPLAY INVISIBLE (-6825 1975);
FORCEPROP 1 LAST OFFPAGE TRUE
J 2
(-7150 1850);
DISPLAY 0.872340 (-7150 1850);
PAINT GREEN (-7150 1850);
DISPLAY INVISIBLE (-7150 1850);
FORCEPROP 1 LAST COMMENT_BODY TRUE
J 2
(-6780 1880);
DISPLAY 0.872340 (-6780 1880);
PAINT GREEN (-6780 1880);
DISPLAY INVISIBLE (-6780 1880);
FORCEPROP 2 LAST PATH I47
J 0
(-6775 2050);
DISPLAY 1.021277 (-6775 2050);
DISPLAY INVISIBLE (-6775 2050);
FORCEADD OFFPAGE..2
R 2
(-6825 1775);
FORCEPROP 2 LAST $XR0 193 
J 0
(-7110 1775);
DISPLAY 0.638298 (-7110 1775);
PAINT MONO (-7110 1775);
FORCEPROP 2 LAST CDS_LIB standard
J 0
(-6825 1775);
DISPLAY INVISIBLE (-6825 1775);
FORCEPROP 1 LAST OFFPAGE TRUE
J 2
(-7150 1650);
DISPLAY 0.872340 (-7150 1650);
PAINT GREEN (-7150 1650);
DISPLAY INVISIBLE (-7150 1650);
FORCEPROP 1 LAST COMMENT_BODY TRUE
J 2
(-6780 1680);
DISPLAY 0.872340 (-6780 1680);
PAINT GREEN (-6780 1680);
DISPLAY INVISIBLE (-6780 1680);
FORCEPROP 2 LAST PATH I50
J 0
(-6775 1850);
DISPLAY 1.021277 (-6775 1850);
DISPLAY INVISIBLE (-6775 1850);
FORCEADD OFFPAGE..2
R 2
(-6825 2325);
FORCEPROP 2 LAST $XR0 193 
J 0
(-7110 2325);
DISPLAY 0.638298 (-7110 2325);
PAINT MONO (-7110 2325);
FORCEPROP 2 LAST CDS_LIB standard
J 0
(-6825 2325);
DISPLAY INVISIBLE (-6825 2325);
FORCEPROP 1 LAST OFFPAGE TRUE
J 2
(-7150 2200);
DISPLAY 0.872340 (-7150 2200);
PAINT GREEN (-7150 2200);
DISPLAY INVISIBLE (-7150 2200);
FORCEPROP 1 LAST COMMENT_BODY TRUE
J 2
(-6780 2230);
DISPLAY 0.872340 (-6780 2230);
PAINT GREEN (-6780 2230);
DISPLAY INVISIBLE (-6780 2230);
FORCEPROP 2 LAST PATH I51
J 0
(-6775 2400);
DISPLAY 1.021277 (-6775 2400);
DISPLAY INVISIBLE (-6775 2400);
FORCEADD OFFPAGE..2
R 2
(-6825 2025);
FORCEPROP 2 LAST $XR0 200 
J 0
(-7110 2025);
DISPLAY 0.638298 (-7110 2025);
PAINT MONO (-7110 2025);
FORCEPROP 2 LAST CDS_LIB standard
J 0
(-6825 2025);
DISPLAY INVISIBLE (-6825 2025);
FORCEPROP 1 LAST OFFPAGE TRUE
J 2
(-7150 1900);
DISPLAY 0.872340 (-7150 1900);
PAINT GREEN (-7150 1900);
DISPLAY INVISIBLE (-7150 1900);
FORCEPROP 1 LAST COMMENT_BODY TRUE
J 2
(-6780 1930);
DISPLAY 0.872340 (-6780 1930);
PAINT GREEN (-6780 1930);
DISPLAY INVISIBLE (-6780 1930);
FORCEPROP 2 LAST PATH I53
J 0
(-6775 2100);
DISPLAY 1.021277 (-6775 2100);
DISPLAY INVISIBLE (-6775 2100);
FORCEADD OFFPAGE..2
R 2
(-6825 2225);
FORCEPROP 2 LAST $XR1 207 
J 0
(-7230 2225);
DISPLAY 0.638298 (-7230 2225);
PAINT MONO (-7230 2225);
FORCEPROP 2 LAST $XR0 200 
J 0
(-7110 2225);
DISPLAY 0.638298 (-7110 2225);
PAINT MONO (-7110 2225);
FORCEPROP 2 LAST CDS_LIB standard
J 0
(-6825 2225);
DISPLAY INVISIBLE (-6825 2225);
FORCEPROP 1 LAST OFFPAGE TRUE
J 2
(-7150 2100);
DISPLAY 0.872340 (-7150 2100);
PAINT GREEN (-7150 2100);
DISPLAY INVISIBLE (-7150 2100);
FORCEPROP 1 LAST COMMENT_BODY TRUE
J 2
(-6780 2130);
DISPLAY 0.872340 (-6780 2130);
PAINT GREEN (-6780 2130);
DISPLAY INVISIBLE (-6780 2130);
FORCEPROP 2 LAST PATH I54
J 0
(-6775 2300);
DISPLAY 1.021277 (-6775 2300);
DISPLAY INVISIBLE (-6775 2300);
FORCEADD OFFPAGE..2
R 2
(-6825 2075);
FORCEPROP 2 LAST $XR0 200 
J 0
(-7110 2075);
DISPLAY 0.638298 (-7110 2075);
PAINT MONO (-7110 2075);
FORCEPROP 2 LAST CDS_LIB standard
J 0
(-6825 2075);
DISPLAY INVISIBLE (-6825 2075);
FORCEPROP 1 LAST OFFPAGE TRUE
J 2
(-7150 1950);
DISPLAY 0.872340 (-7150 1950);
PAINT GREEN (-7150 1950);
DISPLAY INVISIBLE (-7150 1950);
FORCEPROP 1 LAST COMMENT_BODY TRUE
J 2
(-6780 1980);
DISPLAY 0.872340 (-6780 1980);
PAINT GREEN (-6780 1980);
DISPLAY INVISIBLE (-6780 1980);
FORCEPROP 2 LAST PATH I55
J 0
(-6775 2150);
DISPLAY 1.021277 (-6775 2150);
DISPLAY INVISIBLE (-6775 2150);
FORCEADD OFFPAGE..2
R 2
(-6825 2275);
FORCEPROP 2 LAST $XR0 200 
J 0
(-7110 2275);
DISPLAY 0.638298 (-7110 2275);
PAINT MONO (-7110 2275);
FORCEPROP 2 LAST CDS_LIB standard
J 0
(-6825 2275);
DISPLAY INVISIBLE (-6825 2275);
FORCEPROP 1 LAST OFFPAGE TRUE
J 2
(-7150 2150);
DISPLAY 0.872340 (-7150 2150);
PAINT GREEN (-7150 2150);
DISPLAY INVISIBLE (-7150 2150);
FORCEPROP 1 LAST COMMENT_BODY TRUE
J 2
(-6780 2180);
DISPLAY 0.872340 (-6780 2180);
PAINT GREEN (-6780 2180);
DISPLAY INVISIBLE (-6780 2180);
FORCEPROP 2 LAST PATH I56
J 0
(-6775 2350);
DISPLAY 1.021277 (-6775 2350);
DISPLAY INVISIBLE (-6775 2350);
FORCEADD OFFPAGE..2
R 2
(-6825 1925);
FORCEPROP 2 LAST $XR0 207 
J 0
(-7110 1925);
DISPLAY 0.638298 (-7110 1925);
PAINT MONO (-7110 1925);
FORCEPROP 2 LAST CDS_LIB standard
J 0
(-6825 1925);
DISPLAY INVISIBLE (-6825 1925);
FORCEPROP 1 LAST OFFPAGE TRUE
J 2
(-7150 1800);
DISPLAY 0.872340 (-7150 1800);
PAINT GREEN (-7150 1800);
DISPLAY INVISIBLE (-7150 1800);
FORCEPROP 1 LAST COMMENT_BODY TRUE
J 2
(-6780 1830);
DISPLAY 0.872340 (-6780 1830);
PAINT GREEN (-6780 1830);
DISPLAY INVISIBLE (-6780 1830);
FORCEPROP 2 LAST PATH I57
J 0
(-6775 2000);
DISPLAY 1.021277 (-6775 2000);
DISPLAY INVISIBLE (-6775 2000);
FORCEADD OFFPAGE..4
R 2
(-6125 4875);
FORCEPROP 2 LAST $XR0 161 
J 0
(-6407 4875);
DISPLAY 0.638298 (-6407 4875);
PAINT MONO (-6407 4875);
FORCEPROP 2 LAST CDS_LIB standard
J 0
(-6125 4875);
DISPLAY INVISIBLE (-6125 4875);
FORCEPROP 1 LAST OFFPAGE TRUE
J 2
(-6450 4750);
DISPLAY 0.872340 (-6450 4750);
PAINT GREEN (-6450 4750);
DISPLAY INVISIBLE (-6450 4750);
FORCEPROP 1 LAST COMMENT_BODY TRUE
J 2
(-6100 4775);
DISPLAY 0.872340 (-6100 4775);
PAINT GREEN (-6100 4775);
DISPLAY INVISIBLE (-6100 4775);
FORCEPROP 2 LAST PATH I62
J 0
(-6075 4950);
DISPLAY 1.021277 (-6075 4950);
DISPLAY INVISIBLE (-6075 4950);
FORCEADD OFFPAGE..4
R 2
(-6125 4825);
FORCEPROP 2 LAST $XR0 161 
J 0
(-6407 4825);
DISPLAY 0.638298 (-6407 4825);
PAINT MONO (-6407 4825);
FORCEPROP 2 LAST CDS_LIB standard
J 0
(-6125 4825);
DISPLAY INVISIBLE (-6125 4825);
FORCEPROP 1 LAST OFFPAGE TRUE
J 2
(-6450 4700);
DISPLAY 0.872340 (-6450 4700);
PAINT GREEN (-6450 4700);
DISPLAY INVISIBLE (-6450 4700);
FORCEPROP 1 LAST COMMENT_BODY TRUE
J 2
(-6100 4725);
DISPLAY 0.872340 (-6100 4725);
PAINT GREEN (-6100 4725);
DISPLAY INVISIBLE (-6100 4725);
FORCEPROP 2 LAST PATH I63
J 0
(-6075 4900);
DISPLAY 1.021277 (-6075 4900);
DISPLAY INVISIBLE (-6075 4900);
FORCEADD OFFPAGE..2
R 2
(-6825 1825);
FORCEPROP 2 LAST $XR0 209 
J 0
(-7110 1825);
DISPLAY 0.638298 (-7110 1825);
PAINT MONO (-7110 1825);
FORCEPROP 2 LAST CDS_LIB standard
J 0
(-6825 1825);
DISPLAY INVISIBLE (-6825 1825);
FORCEPROP 1 LAST OFFPAGE TRUE
J 2
(-7150 1700);
DISPLAY 0.872340 (-7150 1700);
PAINT GREEN (-7150 1700);
DISPLAY INVISIBLE (-7150 1700);
FORCEPROP 1 LAST COMMENT_BODY TRUE
J 2
(-6780 1730);
DISPLAY 0.872340 (-6780 1730);
PAINT GREEN (-6780 1730);
DISPLAY INVISIBLE (-6780 1730);
FORCEPROP 2 LAST PATH I67
J 0
(-6775 1900);
DISPLAY 1.021277 (-6775 1900);
DISPLAY INVISIBLE (-6775 1900);
FORCEADD OFFPAGE..2
R 2
(-6825 2175);
FORCEPROP 2 LAST $XR0 209 
J 0
(-7110 2175);
DISPLAY 0.638298 (-7110 2175);
PAINT MONO (-7110 2175);
FORCEPROP 2 LAST CDS_LIB standard
J 0
(-6825 2175);
DISPLAY INVISIBLE (-6825 2175);
FORCEPROP 1 LAST OFFPAGE TRUE
J 2
(-7150 2050);
DISPLAY 0.872340 (-7150 2050);
PAINT GREEN (-7150 2050);
DISPLAY INVISIBLE (-7150 2050);
FORCEPROP 1 LAST COMMENT_BODY TRUE
J 2
(-6780 2080);
DISPLAY 0.872340 (-6780 2080);
PAINT GREEN (-6780 2080);
DISPLAY INVISIBLE (-6780 2080);
FORCEPROP 2 LAST PATH I68
J 0
(-6775 2250);
DISPLAY 1.021277 (-6775 2250);
DISPLAY INVISIBLE (-6775 2250);
FORCEADD OFFPAGE..4
R 2
(-5750 5675);
FORCEPROP 2 LAST $XR1 83 
J 0
(-6061 5675);
DISPLAY 0.638298 (-6061 5675);
PAINT MONO (-6061 5675);
FORCEPROP 2 LAST $XR0 81 
J 0
(-5971 5675);
DISPLAY 0.638298 (-5971 5675);
PAINT MONO (-5971 5675);
FORCEPROP 2 LAST CDS_LIB standard
J 0
(-5750 5675);
DISPLAY INVISIBLE (-5750 5675);
FORCEPROP 1 LAST OFFPAGE TRUE
J 2
(-6075 5550);
DISPLAY 0.872340 (-6075 5550);
PAINT GREEN (-6075 5550);
DISPLAY INVISIBLE (-6075 5550);
FORCEPROP 1 LAST COMMENT_BODY TRUE
J 2
(-5725 5575);
DISPLAY 0.872340 (-5725 5575);
PAINT GREEN (-5725 5575);
DISPLAY INVISIBLE (-5725 5575);
FORCEPROP 2 LAST PATH I69
J 0
(-5700 5750);
DISPLAY 1.021277 (-5700 5750);
DISPLAY INVISIBLE (-5700 5750);
FORCEADD OFFPAGE..4
R 2
(-5750 5625);
FORCEPROP 2 LAST $XR1 83 
J 0
(-6061 5625);
DISPLAY 0.638298 (-6061 5625);
PAINT MONO (-6061 5625);
FORCEPROP 2 LAST $XR0 81 
J 0
(-5971 5625);
DISPLAY 0.638298 (-5971 5625);
PAINT MONO (-5971 5625);
FORCEPROP 2 LAST CDS_LIB standard
J 0
(-5750 5625);
DISPLAY INVISIBLE (-5750 5625);
FORCEPROP 1 LAST OFFPAGE TRUE
J 2
(-6075 5500);
DISPLAY 0.872340 (-6075 5500);
PAINT GREEN (-6075 5500);
DISPLAY INVISIBLE (-6075 5500);
FORCEPROP 1 LAST COMMENT_BODY TRUE
J 2
(-5725 5525);
DISPLAY 0.872340 (-5725 5525);
PAINT GREEN (-5725 5525);
DISPLAY INVISIBLE (-5725 5525);
FORCEPROP 2 LAST PATH I70
J 0
(-5700 5700);
DISPLAY 1.021277 (-5700 5700);
DISPLAY INVISIBLE (-5700 5700);
FORCEADD OFFPAGE..2
R 2
(-6125 3075);
FORCEPROP 2 LAST $XR0 167 
J 0
(-6380 3075);
DISPLAY 0.638298 (-6380 3075);
PAINT MONO (-6380 3075);
FORCEPROP 2 LAST CDS_LIB standard
J 0
(-6125 3075);
DISPLAY INVISIBLE (-6125 3075);
FORCEPROP 1 LAST OFFPAGE TRUE
J 2
(-6450 2950);
DISPLAY 0.872340 (-6450 2950);
PAINT GREEN (-6450 2950);
DISPLAY INVISIBLE (-6450 2950);
FORCEPROP 1 LAST COMMENT_BODY TRUE
J 2
(-6080 2980);
DISPLAY 0.872340 (-6080 2980);
PAINT GREEN (-6080 2980);
DISPLAY INVISIBLE (-6080 2980);
FORCEPROP 2 LAST PATH I71
J 0
(-6375 3125);
DISPLAY 1.021277 (-6375 3125);
DISPLAY INVISIBLE (-6375 3125);
FORCEADD OFFPAGE..2
R 2
(-6125 2525);
FORCEPROP 2 LAST $XR1 82 
J 0
(-6439 2525);
DISPLAY 0.638298 (-6439 2525);
PAINT MONO (-6439 2525);
FORCEPROP 2 LAST $XR0 27 
J 0
(-6349 2525);
DISPLAY 0.638298 (-6349 2525);
PAINT MONO (-6349 2525);
FORCEPROP 2 LAST CDS_LIB standard
J 0
(-6125 2525);
DISPLAY INVISIBLE (-6125 2525);
FORCEPROP 1 LAST OFFPAGE TRUE
J 2
(-6450 2400);
DISPLAY 0.872340 (-6450 2400);
PAINT GREEN (-6450 2400);
DISPLAY INVISIBLE (-6450 2400);
FORCEPROP 1 LAST COMMENT_BODY TRUE
J 2
(-6080 2430);
DISPLAY 0.872340 (-6080 2430);
PAINT GREEN (-6080 2430);
DISPLAY INVISIBLE (-6080 2430);
FORCEPROP 2 LAST PATH I72
J 0
(-6375 2575);
DISPLAY 1.021277 (-6375 2575);
DISPLAY INVISIBLE (-6375 2575);
FORCEADD OFFPAGE..2
R 2
(-6125 2475);
FORCEPROP 2 LAST $XR1 82 
J 0
(-6439 2475);
DISPLAY 0.638298 (-6439 2475);
PAINT MONO (-6439 2475);
FORCEPROP 2 LAST $XR0 27 
J 0
(-6349 2475);
DISPLAY 0.638298 (-6349 2475);
PAINT MONO (-6349 2475);
FORCEPROP 2 LAST CDS_LIB standard
J 0
(-6125 2475);
DISPLAY INVISIBLE (-6125 2475);
FORCEPROP 1 LAST OFFPAGE TRUE
J 2
(-6450 2350);
DISPLAY 0.872340 (-6450 2350);
PAINT GREEN (-6450 2350);
DISPLAY INVISIBLE (-6450 2350);
FORCEPROP 1 LAST COMMENT_BODY TRUE
J 2
(-6080 2380);
DISPLAY 0.872340 (-6080 2380);
PAINT GREEN (-6080 2380);
DISPLAY INVISIBLE (-6080 2380);
FORCEPROP 2 LAST PATH I73
J 0
(-6375 2525);
DISPLAY 1.021277 (-6375 2525);
DISPLAY INVISIBLE (-6375 2525);
FORCEADD OFFPAGE..2
(-7725 3100);
FORCEPROP 2 LAST $XR1 82 
J 0
(-7446 3100);
DISPLAY 0.638298 (-7446 3100);
PAINT MONO (-7446 3100);
FORCEPROP 2 LAST $XR0 27 
J 0
(-7536 3100);
DISPLAY 0.638298 (-7536 3100);
PAINT MONO (-7536 3100);
FORCEPROP 2 LAST CDS_LIB standard
J 0
(-7725 3100);
DISPLAY INVISIBLE (-7725 3100);
FORCEPROP 1 LAST OFFPAGE TRUE
J 0
(-7400 2975);
DISPLAY 0.872340 (-7400 2975);
PAINT GREEN (-7400 2975);
DISPLAY INVISIBLE (-7400 2975);
FORCEPROP 1 LAST COMMENT_BODY TRUE
J 0
(-7770 3005);
DISPLAY 0.872340 (-7770 3005);
PAINT PEACH (-7770 3005);
DISPLAY INVISIBLE (-7770 3005);
FORCEPROP 2 LAST PATH I74
J 2
(-7525 3150);
DISPLAY 1.021277 (-7525 3150);
DISPLAY INVISIBLE (-7525 3150);
FORCEADD OFFPAGE..2
(-7725 3150);
FORCEPROP 2 LAST $XR1 82 
J 0
(-7446 3150);
DISPLAY 0.638298 (-7446 3150);
PAINT MONO (-7446 3150);
FORCEPROP 2 LAST $XR0 27 
J 0
(-7536 3150);
DISPLAY 0.638298 (-7536 3150);
PAINT MONO (-7536 3150);
FORCEPROP 2 LAST CDS_LIB standard
J 0
(-7725 3150);
DISPLAY INVISIBLE (-7725 3150);
FORCEPROP 1 LAST OFFPAGE TRUE
J 0
(-7400 3025);
DISPLAY 0.872340 (-7400 3025);
PAINT GREEN (-7400 3025);
DISPLAY INVISIBLE (-7400 3025);
FORCEPROP 1 LAST COMMENT_BODY TRUE
J 0
(-7770 3055);
DISPLAY 0.872340 (-7770 3055);
PAINT PEACH (-7770 3055);
DISPLAY INVISIBLE (-7770 3055);
FORCEPROP 2 LAST PATH I75
J 2
(-7525 3200);
DISPLAY 1.021277 (-7525 3200);
DISPLAY INVISIBLE (-7525 3200);
FORCEADD OFFPAGE..2
R 2
(-6125 2775);
FORCEPROP 2 LAST $XR1 82 
J 0
(-6439 2775);
DISPLAY 0.638298 (-6439 2775);
PAINT MONO (-6439 2775);
FORCEPROP 2 LAST $XR0 27 
J 0
(-6349 2775);
DISPLAY 0.638298 (-6349 2775);
PAINT MONO (-6349 2775);
FORCEPROP 2 LAST CDS_LIB standard
J 0
(-6125 2775);
DISPLAY INVISIBLE (-6125 2775);
FORCEPROP 1 LAST OFFPAGE TRUE
J 2
(-6450 2650);
DISPLAY 0.872340 (-6450 2650);
PAINT GREEN (-6450 2650);
DISPLAY INVISIBLE (-6450 2650);
FORCEPROP 1 LAST COMMENT_BODY TRUE
J 2
(-6080 2680);
DISPLAY 0.872340 (-6080 2680);
PAINT GREEN (-6080 2680);
DISPLAY INVISIBLE (-6080 2680);
FORCEPROP 2 LAST PATH I79
J 0
(-6375 2825);
DISPLAY 1.021277 (-6375 2825);
DISPLAY INVISIBLE (-6375 2825);
FORCEADD OFFPAGE..2
R 2
(-6125 2725);
FORCEPROP 2 LAST $XR1 82 
J 0
(-6439 2725);
DISPLAY 0.638298 (-6439 2725);
PAINT MONO (-6439 2725);
FORCEPROP 2 LAST $XR0 27 
J 0
(-6349 2725);
DISPLAY 0.638298 (-6349 2725);
PAINT MONO (-6349 2725);
FORCEPROP 2 LAST CDS_LIB standard
J 0
(-6125 2725);
DISPLAY INVISIBLE (-6125 2725);
FORCEPROP 1 LAST OFFPAGE TRUE
J 2
(-6450 2600);
DISPLAY 0.872340 (-6450 2600);
PAINT GREEN (-6450 2600);
DISPLAY INVISIBLE (-6450 2600);
FORCEPROP 1 LAST COMMENT_BODY TRUE
J 2
(-6080 2630);
DISPLAY 0.872340 (-6080 2630);
PAINT GREEN (-6080 2630);
DISPLAY INVISIBLE (-6080 2630);
FORCEPROP 2 LAST PATH I80
J 0
(-6375 2775);
DISPLAY 1.021277 (-6375 2775);
DISPLAY INVISIBLE (-6375 2775);
FORCEADD OFFPAGE..2
R 2
(-6125 2675);
FORCEPROP 2 LAST $XR1 82 
J 0
(-6439 2675);
DISPLAY 0.638298 (-6439 2675);
PAINT MONO (-6439 2675);
FORCEPROP 2 LAST $XR0 27 
J 0
(-6349 2675);
DISPLAY 0.638298 (-6349 2675);
PAINT MONO (-6349 2675);
FORCEPROP 2 LAST CDS_LIB standard
J 0
(-6125 2675);
DISPLAY INVISIBLE (-6125 2675);
FORCEPROP 1 LAST OFFPAGE TRUE
J 2
(-6450 2550);
DISPLAY 0.872340 (-6450 2550);
PAINT GREEN (-6450 2550);
DISPLAY INVISIBLE (-6450 2550);
FORCEPROP 1 LAST COMMENT_BODY TRUE
J 2
(-6080 2580);
DISPLAY 0.872340 (-6080 2580);
PAINT GREEN (-6080 2580);
DISPLAY INVISIBLE (-6080 2580);
FORCEPROP 2 LAST PATH I81
J 0
(-6375 2725);
DISPLAY 1.021277 (-6375 2725);
DISPLAY INVISIBLE (-6375 2725);
FORCEADD OFFPAGE..2
R 2
(-6125 2625);
FORCEPROP 2 LAST $XR1 82 
J 0
(-6439 2625);
DISPLAY 0.638298 (-6439 2625);
PAINT MONO (-6439 2625);
FORCEPROP 2 LAST $XR0 27 
J 0
(-6349 2625);
DISPLAY 0.638298 (-6349 2625);
PAINT MONO (-6349 2625);
FORCEPROP 2 LAST CDS_LIB standard
J 0
(-6125 2625);
DISPLAY INVISIBLE (-6125 2625);
FORCEPROP 1 LAST OFFPAGE TRUE
J 2
(-6450 2500);
DISPLAY 0.872340 (-6450 2500);
PAINT GREEN (-6450 2500);
DISPLAY INVISIBLE (-6450 2500);
FORCEPROP 1 LAST COMMENT_BODY TRUE
J 2
(-6080 2530);
DISPLAY 0.872340 (-6080 2530);
PAINT GREEN (-6080 2530);
DISPLAY INVISIBLE (-6080 2530);
FORCEPROP 2 LAST PATH I82
J 0
(-6375 2675);
DISPLAY 1.021277 (-6375 2675);
DISPLAY INVISIBLE (-6375 2675);
FORCEADD OFFPAGE..2
(-7725 3050);
FORCEPROP 2 LAST $XR1 82 
J 0
(-7446 3050);
DISPLAY 0.638298 (-7446 3050);
PAINT MONO (-7446 3050);
FORCEPROP 2 LAST $XR0 27 
J 0
(-7536 3050);
DISPLAY 0.638298 (-7536 3050);
PAINT MONO (-7536 3050);
FORCEPROP 2 LAST CDS_LIB standard
J 0
(-7725 3050);
DISPLAY INVISIBLE (-7725 3050);
FORCEPROP 1 LAST OFFPAGE TRUE
J 0
(-7400 2925);
DISPLAY 0.872340 (-7400 2925);
PAINT GREEN (-7400 2925);
DISPLAY INVISIBLE (-7400 2925);
FORCEPROP 1 LAST COMMENT_BODY TRUE
J 0
(-7770 2955);
DISPLAY 0.872340 (-7770 2955);
PAINT PEACH (-7770 2955);
DISPLAY INVISIBLE (-7770 2955);
FORCEPROP 2 LAST PATH I85
J 0
(-7550 3125);
DISPLAY 1.021277 (-7550 3125);
DISPLAY INVISIBLE (-7550 3125);
FORCEADD OFFPAGE..2
(-7725 3000);
FORCEPROP 2 LAST $XR1 82 
J 0
(-7446 3000);
DISPLAY 0.638298 (-7446 3000);
PAINT MONO (-7446 3000);
FORCEPROP 2 LAST $XR0 27 
J 0
(-7536 3000);
DISPLAY 0.638298 (-7536 3000);
PAINT MONO (-7536 3000);
FORCEPROP 2 LAST CDS_LIB standard
J 0
(-7725 3000);
DISPLAY INVISIBLE (-7725 3000);
FORCEPROP 1 LAST OFFPAGE TRUE
J 0
(-7400 2875);
DISPLAY 0.872340 (-7400 2875);
PAINT GREEN (-7400 2875);
DISPLAY INVISIBLE (-7400 2875);
FORCEPROP 1 LAST COMMENT_BODY TRUE
J 0
(-7770 2905);
DISPLAY 0.872340 (-7770 2905);
PAINT PEACH (-7770 2905);
DISPLAY INVISIBLE (-7770 2905);
FORCEPROP 2 LAST PATH I86
J 0
(-7550 3075);
DISPLAY 1.021277 (-7550 3075);
DISPLAY INVISIBLE (-7550 3075);
FORCEADD OFFPAGE..2
(-7775 4525);
FORCEPROP 2 LAST $XR1 27 
J 0
(-7496 4525);
DISPLAY 0.638298 (-7496 4525);
PAINT MONO (-7496 4525);
FORCEPROP 2 LAST $XR0 82 
J 0
(-7586 4525);
DISPLAY 0.638298 (-7586 4525);
PAINT MONO (-7586 4525);
FORCEPROP 2 LAST CDS_LIB standard
J 0
(-7775 4525);
DISPLAY INVISIBLE (-7775 4525);
FORCEPROP 1 LAST OFFPAGE TRUE
J 0
(-7450 4400);
DISPLAY 0.872340 (-7450 4400);
PAINT GREEN (-7450 4400);
DISPLAY INVISIBLE (-7450 4400);
FORCEPROP 1 LAST COMMENT_BODY TRUE
J 0
(-7820 4430);
DISPLAY 0.872340 (-7820 4430);
PAINT PEACH (-7820 4430);
DISPLAY INVISIBLE (-7820 4430);
FORCEPROP 2 LAST PATH I87
J 0
(-7575 4575);
DISPLAY 1.021277 (-7575 4575);
DISPLAY INVISIBLE (-7575 4575);
FORCEADD OFFPAGE..2
(-7775 4475);
FORCEPROP 2 LAST $XR1 27 
J 0
(-7496 4475);
DISPLAY 0.638298 (-7496 4475);
PAINT MONO (-7496 4475);
FORCEPROP 2 LAST $XR0 82 
J 0
(-7586 4475);
DISPLAY 0.638298 (-7586 4475);
PAINT MONO (-7586 4475);
FORCEPROP 2 LAST CDS_LIB standard
J 0
(-7775 4475);
DISPLAY INVISIBLE (-7775 4475);
FORCEPROP 1 LAST OFFPAGE TRUE
J 0
(-7450 4350);
DISPLAY 0.872340 (-7450 4350);
PAINT GREEN (-7450 4350);
DISPLAY INVISIBLE (-7450 4350);
FORCEPROP 1 LAST COMMENT_BODY TRUE
J 0
(-7820 4380);
DISPLAY 0.872340 (-7820 4380);
PAINT PEACH (-7820 4380);
DISPLAY INVISIBLE (-7820 4380);
FORCEPROP 2 LAST PATH I88
J 0
(-7575 4525);
DISPLAY 1.021277 (-7575 4525);
DISPLAY INVISIBLE (-7575 4525);
FORCEADD OFFPAGE..4
R 2
(-6125 2975);
FORCEPROP 2 LAST $XR1 82 
J 0
(-6466 2975);
DISPLAY 0.638298 (-6466 2975);
PAINT MONO (-6466 2975);
FORCEPROP 2 LAST $XR0 27 
J 0
(-6376 2975);
DISPLAY 0.638298 (-6376 2975);
PAINT MONO (-6376 2975);
FORCEPROP 2 LAST CDS_LIB standard
J 0
(-6125 2975);
DISPLAY INVISIBLE (-6125 2975);
FORCEPROP 1 LAST OFFPAGE TRUE
J 2
(-6450 2850);
DISPLAY 0.872340 (-6450 2850);
PAINT GREEN (-6450 2850);
DISPLAY INVISIBLE (-6450 2850);
FORCEPROP 1 LAST COMMENT_BODY TRUE
J 2
(-6100 2875);
DISPLAY 0.872340 (-6100 2875);
PAINT GREEN (-6100 2875);
DISPLAY INVISIBLE (-6100 2875);
FORCEPROP 2 LAST PATH I92
J 0
(-6375 3025);
DISPLAY 1.021277 (-6375 3025);
DISPLAY INVISIBLE (-6375 3025);
FORCEADD OFFPAGE..4
R 2
(-6125 2925);
FORCEPROP 2 LAST $XR1 82 
J 0
(-6466 2925);
DISPLAY 0.638298 (-6466 2925);
PAINT MONO (-6466 2925);
FORCEPROP 2 LAST $XR0 27 
J 0
(-6376 2925);
DISPLAY 0.638298 (-6376 2925);
PAINT MONO (-6376 2925);
FORCEPROP 2 LAST CDS_LIB standard
J 0
(-6125 2925);
DISPLAY INVISIBLE (-6125 2925);
FORCEPROP 1 LAST OFFPAGE TRUE
J 2
(-6450 2800);
DISPLAY 0.872340 (-6450 2800);
PAINT GREEN (-6450 2800);
DISPLAY INVISIBLE (-6450 2800);
FORCEPROP 1 LAST COMMENT_BODY TRUE
J 2
(-6100 2825);
DISPLAY 0.872340 (-6100 2825);
PAINT GREEN (-6100 2825);
DISPLAY INVISIBLE (-6100 2825);
FORCEPROP 2 LAST PATH I93
J 0
(-6375 2975);
DISPLAY 1.021277 (-6375 2975);
DISPLAY INVISIBLE (-6375 2975);
FORCEADD GND..1
(-8550 4150);
FORCEPROP 3 LASTPIN (-8550 4200) SIG_NAME GND\g
J 0
(-8540 4210);
DISPLAY 0.659574 (-8540 4210);
PAINT MONO (-8540 4210);
DISPLAY INVISIBLE (-8540 4210);
FORCEPROP 1 LAST SIZE 1B
J 0
(-8475 4100);
DISPLAY 0.872340 (-8475 4100);
PAINT GREEN (-8475 4100);
DISPLAY INVISIBLE (-8475 4100);
FORCEPROP 2 LAST CDS_LIB pure_quanta_power
J 0
(-8550 4150);
DISPLAY INVISIBLE (-8550 4150);
FORCEPROP 1 LAST HDL_POWER GND
J 0
(-8550 4300);
DISPLAY 0.872340 (-8550 4300);
PAINT GREEN (-8550 4300);
DISPLAY INVISIBLE (-8550 4300);
FORCEPROP 1 LAST PATH I95
J 0
(-8475 4150);
DISPLAY 0.872340 (-8475 4150);
PAINT AQUA (-8475 4150);
DISPLAY INVISIBLE (-8475 4150);
FORCEADD GND..1
(-8675 4150);
FORCEPROP 3 LASTPIN (-8675 4200) SIG_NAME GND\g
J 0
(-8665 4210);
DISPLAY 0.659574 (-8665 4210);
PAINT MONO (-8665 4210);
DISPLAY INVISIBLE (-8665 4210);
FORCEPROP 1 LAST SIZE 1B
J 0
(-8600 4100);
DISPLAY 0.872340 (-8600 4100);
PAINT GREEN (-8600 4100);
DISPLAY INVISIBLE (-8600 4100);
FORCEPROP 2 LAST CDS_LIB pure_quanta_power
J 0
(-8675 4150);
DISPLAY INVISIBLE (-8675 4150);
FORCEPROP 1 LAST HDL_POWER GND
J 0
(-8675 4300);
DISPLAY 0.872340 (-8675 4300);
PAINT GREEN (-8675 4300);
DISPLAY INVISIBLE (-8675 4300);
FORCEPROP 1 LAST PATH I96
J 0
(-8600 4150);
DISPLAY 0.872340 (-8600 4150);
PAINT AQUA (-8600 4150);
DISPLAY INVISIBLE (-8600 4150);
FORCEADD DNS..2
(-5625 900);
PAINT RED (-5625 900);
FORCEPROP 2 LAST CDS_LIB mstr_misc
J 0
(-5625 900);
DISPLAY INVISIBLE (-5625 900);
FORCEPROP 1 LAST COMMENT_BODY TRUE
J 0
(-5625 900);
PAINT RED (-5625 900);
DISPLAY INVISIBLE (-5625 900);
FORCEADD DNS..2
(-6400 575);
PAINT RED (-6400 575);
FORCEPROP 2 LAST CDS_LIB mstr_misc
J 0
(-6400 575);
DISPLAY INVISIBLE (-6400 575);
FORCEPROP 1 LAST COMMENT_BODY TRUE
J 0
(-6400 575);
PAINT RED (-6400 575);
DISPLAY INVISIBLE (-6400 575);
FORCEADD DNS..2
(-8650 4650);
PAINT RED (-8650 4650);
FORCEPROP 2 LAST CDS_LIB mstr_misc
J 0
(-8650 4650);
DISPLAY INVISIBLE (-8650 4650);
FORCEPROP 1 LAST COMMENT_BODY TRUE
J 0
(-8650 4650);
PAINT RED (-8650 4650);
DISPLAY INVISIBLE (-8650 4650);
FORCEADD DNS..2
(-8025 575);
PAINT RED (-8025 575);
FORCEPROP 2 LAST CDS_LIB mstr_misc
J 0
(-8025 575);
PAINT MONO (-8025 575);
DISPLAY INVISIBLE (-8025 575);
FORCEPROP 1 LAST COMMENT_BODY TRUE
J 0
(-8025 575);
PAINT RED (-8025 575);
DISPLAY INVISIBLE (-8025 575);
FORCEADD DNS..2
(-6675 575);
PAINT RED (-6675 575);
FORCEPROP 2 LAST CDS_LIB mstr_misc
J 0
(-6675 575);
DISPLAY INVISIBLE (-6675 575);
FORCEPROP 1 LAST COMMENT_BODY TRUE
J 0
(-6675 575);
PAINT RED (-6675 575);
DISPLAY INVISIBLE (-6675 575);
FORCEADD DNS..2
(-7050 575);
PAINT RED (-7050 575);
FORCEPROP 2 LAST CDS_LIB mstr_misc
J 0
(-7050 575);
DISPLAY INVISIBLE (-7050 575);
FORCEPROP 1 LAST COMMENT_BODY TRUE
J 0
(-7050 575);
PAINT RED (-7050 575);
DISPLAY INVISIBLE (-7050 575);
FORCEADD DNS..2
(-7375 575);
PAINT RED (-7375 575);
FORCEPROP 2 LAST CDS_LIB mstr_misc
J 0
(-7375 575);
DISPLAY INVISIBLE (-7375 575);
FORCEPROP 1 LAST COMMENT_BODY TRUE
J 0
(-7375 575);
PAINT RED (-7375 575);
DISPLAY INVISIBLE (-7375 575);
FORCEADD DNS..2
(-7700 575);
PAINT RED (-7700 575);
FORCEPROP 2 LAST CDS_LIB mstr_misc
J 0
(-7700 575);
DISPLAY INVISIBLE (-7700 575);
FORCEPROP 1 LAST COMMENT_BODY TRUE
J 0
(-7700 575);
PAINT RED (-7700 575);
DISPLAY INVISIBLE (-7700 575);
FORCEADD QUANTA_TITLE_BLOCK_C..1
(0 0);
FORCEPROP 0 LAST CDS_CON_LAST_MODIFIED Thu Sep 14 16:11:52 2023
J 0
(-1885 15);
DISPLAY INVISIBLE (-1885 15);
FORCEPROP 1 LAST CUSTOM_TXT_CDS <CON_LAST_MODIFIED>
J 0
(-1885 15);
DISPLAY 0.978723 (-1885 15);
FORCEPROP 2 LAST CUSTOM_TXT_CDS <XR_PAGE_TITLE>
J 0
(-7890 5250);
DISPLAY 0.638298 (-7890 5250);
PAINT PINK (-7890 5250);
DISPLAY INVISIBLE (-7890 5250);
FORCEPROP 1 LAST CUSTOM_TXT_CDS <NAME_2>
J 0
(-3175 50);
FORCEPROP 1 LAST CUSTOM_TXT_CDS <NAME_1>
J 0
(-3175 175);
FORCEPROP 1 LAST CUSTOM_TXT_CDS <Q_NUMBER>
J 0
(-1403 103);
DISPLAY 1.212766 (-1403 103);
FORCEPROP 1 LAST CUSTOM_TXT_CDS <Q_PROJ>
J 0
(-2382 102);
DISPLAY 1.212766 (-2382 102);
FORCEPROP 1 LAST CUSTOM_TXT_CDS <Q_REV>
J 0
(-184 103);
DISPLAY 1.212766 (-184 103);
FORCEPROP 1 LAST CUSTOM_TXT_CDS <CON_PAGE_NUM> OF <CON_TOTAL_PAGES>
J 0
(-446 18);
DISPLAY 0.978723 (-446 18);
FORCEPROP 1 LAST Q_TITLE CPU0 MISC 1/2
J 0
(-9275 75);
DISPLAY 2.446809 (-9275 75);
PAINT GREEN (-9275 75);
FORCEPROP 2 LAST CDS_LIB pure_quanta
J 0
(0 0);
DISPLAY INVISIBLE (0 0);
FORCEPROP 1 LAST CDS_LMAN_SYM_OUTLINE -9475,6775,100,-125
J 0
(0 0);
DISPLAY 0.468085 (0 0);
PAINT GREEN (0 0);
DISPLAY INVISIBLE (0 0);
FORCEPROP 2 LAST PAGE_BORDER TRUE
J 0
(-7890 5250);
DISPLAY 0.638298 (-7890 5250);
PAINT PINK (-7890 5250);
DISPLAY INVISIBLE (-7890 5250);
FORCEPROP 2 LAST CDS_XR_PAGE_TITLE CR-27 : @T6G_MB_LIB.T6G(SCH_1):PAGE27
J 0
(-7890 5250);
DISPLAY 0.638298 (-7890 5250);
PAINT PINK (-7890 5250);
DISPLAY INVISIBLE (-7890 5250);
FORCEPROP 1 LAST Q_DEPT BU9
J 1
(-3763 49);
DISPLAY 1.957447 (-3763 49);
PAINT GREEN (-3763 49);
DISPLAY INVISIBLE (-3763 49);
FORCEPROP 1 LAST COMMENT_BODY TRUE
J 0
(12 -13);
DISPLAY 0.978723 (12 -13);
PAINT GREEN (12 -13);
DISPLAY INVISIBLE (12 -13);
WIRE 16 -1 (-8675 4750)(-8675 4775);
WIRE 16 -1 (-6375 500)(-6375 350);
WIRE 16 -1 (-6675 500)(-6675 350);
WIRE 16 -1 (-7350 500)(-7350 350);
WIRE 16 -1 (-7025 500)(-7025 350);
WIRE 16 -1 (-8000 500)(-8000 350);
WIRE 16 -1 (-7675 500)(-7675 350);
WIRE 16 -1 (-5650 1450)(-5650 1525);
WIRE 16 -1 (-5650 800)(-5650 675);
WIRE 16 -1 (-8550 4250)(-8550 4200);
WIRE 16 -1 (-8675 4250)(-8675 4200);
WIRE 16 -1 (-2475 1375)(-3525 1375);
FORCEPROP 2 LAST SIG_NAME UART_CPU0_SCM_UART1_R_TX
J 0
(-3285 1385);
DISPLAY 0.489362 (-3285 1385);
FORCEPROP 2 LASTPROP $XRERR UNIQUE?
J 0
(-3525 1385);
DISPLAY 0.638298 (-3525 1385);
PAINT MONO (-3525 1385);
DISPLAY INVISIBLE (-3525 1385);
WIRE 16 -1 (-3525 1525)(-2725 1525);
FORCEPROP 2 LAST SIG_NAME TP_CPU0_UART0_INTR
J 0
(-3270 1535);
DISPLAY 0.489362 (-3270 1535);
FORCEPROP 2 LASTPROP $XRERR UNIQUE?
J 0
(-2695 1525);
DISPLAY 0.638298 (-2695 1525);
PAINT MONO (-2695 1525);
DISPLAY INVISIBLE (-2695 1525);
WIRE 16 -1 (-3525 1575)(-2600 1575);
FORCEPROP 2 LAST SIG_NAME TP_UART_CPU0_UART0_RTS_N
J 0
(-3285 1585);
DISPLAY 0.489362 (-3285 1585);
FORCEPROP 2 LASTPROP $XRERR UNIQUE?
J 0
(-2570 1575);
DISPLAY 0.638298 (-2570 1575);
PAINT MONO (-2570 1575);
DISPLAY INVISIBLE (-2570 1575);
WIRE 16 -1 (-3525 2075)(-2750 2075);
FORCEPROP 2 LAST SIG_NAME TP_CPU0_TEST5_CCD8
J 0
(-3290 2085);
DISPLAY 0.489362 (-3290 2085);
FORCEPROP 2 LASTPROP $XRERR UNIQUE?
J 0
(-2720 2075);
DISPLAY 0.638298 (-2720 2075);
PAINT MONO (-2720 2075);
DISPLAY INVISIBLE (-2720 2075);
WIRE 16 -1 (-3525 2125)(-2750 2125);
FORCEPROP 2 LAST SIG_NAME TP_CPU0_TEST5_CCD7
J 0
(-3290 2135);
DISPLAY 0.489362 (-3290 2135);
FORCEPROP 2 LASTPROP $XRERR UNIQUE?
J 0
(-2720 2125);
DISPLAY 0.638298 (-2720 2125);
PAINT MONO (-2720 2125);
DISPLAY INVISIBLE (-2720 2125);
WIRE 16 -1 (-3525 2225)(-2750 2225);
FORCEPROP 2 LAST SIG_NAME TP_CPU0_TEST5_CCD5
J 0
(-3290 2235);
DISPLAY 0.489362 (-3290 2235);
FORCEPROP 2 LASTPROP $XRERR UNIQUE?
J 0
(-2720 2225);
DISPLAY 0.638298 (-2720 2225);
PAINT MONO (-2720 2225);
DISPLAY INVISIBLE (-2720 2225);
WIRE 16 -1 (-3525 2425)(-2750 2425);
FORCEPROP 2 LAST SIG_NAME TP_CPU0_TEST5_CCD1
J 0
(-3290 2435);
DISPLAY 0.489362 (-3290 2435);
FORCEPROP 2 LASTPROP $XRERR UNIQUE?
J 0
(-2720 2425);
DISPLAY 0.638298 (-2720 2425);
PAINT MONO (-2720 2425);
DISPLAY INVISIBLE (-2720 2425);
WIRE 16 -1 (-3525 2475)(-2750 2475);
FORCEPROP 2 LAST SIG_NAME TP_CPU0_TEST5_CCD0
J 0
(-3290 2485);
DISPLAY 0.489362 (-3290 2485);
FORCEPROP 2 LASTPROP $XRERR UNIQUE?
J 0
(-2720 2475);
DISPLAY 0.638298 (-2720 2475);
PAINT MONO (-2720 2475);
DISPLAY INVISIBLE (-2720 2475);
WIRE 16 -1 (-3525 2575)(-2750 2575);
FORCEPROP 2 LAST SIG_NAME TP_CPU0_TEST4_CCD11
J 0
(-3290 2585);
DISPLAY 0.489362 (-3290 2585);
FORCEPROP 2 LASTPROP $XRERR UNIQUE?
J 0
(-2720 2575);
DISPLAY 0.638298 (-2720 2575);
PAINT MONO (-2720 2575);
DISPLAY INVISIBLE (-2720 2575);
WIRE 16 -1 (-3525 3425)(-2750 3425);
FORCEPROP 2 LAST SIG_NAME TP_CPU0_TEST6_X3D3
J 0
(-3290 3435);
DISPLAY 0.489362 (-3290 3435);
FORCEPROP 2 LASTPROP $XRERR UNIQUE?
J 0
(-2720 3425);
DISPLAY 0.638298 (-2720 3425);
PAINT MONO (-2720 3425);
DISPLAY INVISIBLE (-2720 3425);
WIRE 16 -1 (-6125 3575)(-5025 3575);
FORCEPROP 2 LAST SIG_NAME TP_CPU0_TEST47_IOD0
J 0
(-5885 3585);
DISPLAY 0.489362 (-5885 3585);
FORCEPROP 2 LASTPROP $XRERR UNIQUE?
J 0
(-6365 3575);
DISPLAY 0.638298 (-6365 3575);
PAINT MONO (-6365 3575);
DISPLAY INVISIBLE (-6365 3575);
WIRE 16 -1 (-5025 3675)(-6125 3675);
FORCEPROP 2 LAST SIG_NAME TP_CPU0_TEST47_CCD3
J 0
(-5885 3685);
DISPLAY 0.489362 (-5885 3685);
FORCEPROP 2 LASTPROP $XRERR UNIQUE?
J 0
(-6365 3675);
DISPLAY 0.638298 (-6365 3675);
PAINT MONO (-6365 3675);
DISPLAY INVISIBLE (-6365 3675);
WIRE 16 -1 (-5025 3525)(-6125 3525);
FORCEPROP 2 LAST SIG_NAME TP_CPU0_TEST47_IOD1
J 0
(-5885 3535);
DISPLAY 0.489362 (-5885 3535);
FORCEPROP 2 LASTPROP $XRERR UNIQUE?
J 0
(-6365 3525);
DISPLAY 0.638298 (-6365 3525);
PAINT MONO (-6365 3525);
DISPLAY INVISIBLE (-6365 3525);
WIRE 16 -1 (-1650 3825)(-1175 3825);
FORCEPROP 2 LAST SIG_NAME CPU0_THERMTRIP_R_N
J 0
(-1785 3910);
DISPLAY 0.553191 (-1785 3910);
WIRE 16 -1 (-975 3825)(-475 3825);
FORCEPROP 2 LAST SIG_NAME CPU1_THERMTRIP_R_N
J 0
(-835 3910);
DISPLAY 0.553191 (-835 3910);
WIRE 16 -1 (-5650 1125)(-5025 1125);
FORCEPROP 2 LAST SIG_NAME CPU0_RTC_LDO_SELECT
J 0
(-5585 1135);
DISPLAY 0.510638 (-5585 1135);
PAINT WHITE (-5585 1135);
FORCEPROP 2 LASTPROP $XRERR UNIQUE?
J 0
(-5825 1135);
DISPLAY 0.638298 (-5825 1135);
PAINT MONO (-5825 1135);
DISPLAY INVISIBLE (-5825 1135);
WIRE 16 -1 (-5650 1250)(-5650 1125);
WIRE 16 -1 (-5650 1125)(-5650 1000);
WIRE 16 -1 (-6775 1775)(-5900 1775);
WIRE 16 -1 (-5900 1775)(-5025 1775);
FORCEPROP 2 LAST SIG_NAME VSENSE_PVDDCR_SOC_P0_DP
J 2
(-5435 1785);
DISPLAY 0.489362 (-5435 1785);
WIRE 16 -1 (-5900 1675)(-5900 1775);
WIRE 16 -1 (-6775 1825)(-5975 1825);
WIRE 16 -1 (-5975 1825)(-5025 1825);
FORCEPROP 2 LAST SIG_NAME VSENSE_PVDD18_S5_P0_DP
J 2
(-5460 1835);
DISPLAY 0.489362 (-5460 1835);
WIRE 16 -1 (-5975 1825)(-5975 1675);
WIRE 16 -1 (-8550 4475)(-7825 4475);
FORCEPROP 2 LAST SIG_NAME CPU0_SA1
J 0
(-8310 4485);
DISPLAY 0.489362 (-8310 4485);
WIRE 16 -1 (-8550 4475)(-8550 4450);
WIRE 16 -1 (-7475 5475)(-6450 5475);
FORCEPROP 2 LAST SIG_NAME SVID_PVDDCR_CPU0_P0_SVD_R
J 0
(-7275 5485);
DISPLAY 0.489362 (-7275 5485);
WIRE 16 -1 (-7475 5275)(-6450 5275);
FORCEPROP 2 LAST SIG_NAME SVID_PVDDCR_CPU1_P0_SVD_R
J 0
(-7275 5285);
DISPLAY 0.489362 (-7275 5285);
WIRE 16 -1 (-6450 5325)(-7475 5325);
FORCEPROP 2 LAST SIG_NAME SVID_PVDDCR_CPU1_P0_SVC_R
J 0
(-7275 5335);
DISPLAY 0.489362 (-7275 5335);
WIRE 16 -1 (-6250 5475)(-5025 5475);
FORCEPROP 2 LAST SIG_NAME SVID_PVDDCR_CPU0_P0_SVD
J 0
(-5760 5485);
DISPLAY 0.489362 (-5760 5485);
FORCEPROP 2 LASTPROP $XRERR UNIQUE?
J 0
(-6000 5485);
DISPLAY 0.638298 (-6000 5485);
PAINT MONO (-6000 5485);
DISPLAY INVISIBLE (-6000 5485);
WIRE 16 -1 (-6250 5525)(-5025 5525);
FORCEPROP 2 LAST SIG_NAME SVID_PVDDCR_CPU0_P0_SVC
J 0
(-5760 5535);
DISPLAY 0.489362 (-5760 5535);
FORCEPROP 2 LASTPROP $XRERR UNIQUE?
J 0
(-6000 5535);
DISPLAY 0.638298 (-6000 5535);
PAINT MONO (-6000 5535);
DISPLAY INVISIBLE (-6000 5535);
WIRE 16 -1 (-5700 5425)(-5025 5425);
FORCEPROP 2 LAST SIG_NAME SVID_PVDDCR_CPU0_P0_SVTO
J 0
(-5685 5435);
DISPLAY 0.489362 (-5685 5435);
WIRE 16 -1 (-6250 5325)(-5025 5325);
FORCEPROP 2 LAST SIG_NAME SVID_PVDDCR_CPU1_P0_SVC
J 0
(-5685 5335);
DISPLAY 0.489362 (-5685 5335);
FORCEPROP 2 LASTPROP $XRERR UNIQUE?
J 0
(-5925 5335);
DISPLAY 0.638298 (-5925 5335);
PAINT MONO (-5925 5335);
DISPLAY INVISIBLE (-5925 5335);
WIRE 16 -1 (-6250 5275)(-5025 5275);
FORCEPROP 2 LAST SIG_NAME SVID_PVDDCR_CPU1_P0_SVD
J 0
(-5685 5285);
DISPLAY 0.489362 (-5685 5285);
FORCEPROP 2 LASTPROP $XRERR UNIQUE?
J 0
(-5925 5285);
DISPLAY 0.638298 (-5925 5285);
PAINT MONO (-5925 5285);
DISPLAY INVISIBLE (-5925 5285);
WIRE 16 -1 (-3525 4775)(-2025 4775);
FORCEPROP 2 LAST SIG_NAME CPU0_PROCHOT_N
J 0
(-3325 4785);
DISPLAY 0.489362 (-3325 4785);
WIRE 16 -1 (-5975 1875)(-5025 1875);
FORCEPROP 2 LAST SIG_NAME TP_VSENSE_PVDD33_S5_P0
J 2
(-5445 1885);
DISPLAY 0.489362 (-5445 1885);
FORCEPROP 2 LASTPROP $XRERR UNIQUE?
J 0
(-6215 1875);
DISPLAY 0.638298 (-6215 1875);
PAINT MONO (-6215 1875);
DISPLAY INVISIBLE (-6215 1875);
WIRE 16 -1 (-6200 1675)(-6200 1975);
WIRE 16 -1 (-6200 1975)(-5025 1975);
FORCEPROP 2 LAST SIG_NAME VSENSE_PVDDCR_CPU0_P0_DP
J 2
(-5410 1985);
DISPLAY 0.489362 (-5410 1985);
WIRE 16 -1 (-6775 1975)(-6200 1975);
WIRE 16 -1 (-5025 2025)(-6275 2025);
FORCEPROP 2 LAST SIG_NAME VSENSE_PVDDCR_CPU1_P0_DP
J 0
(-5960 2035);
DISPLAY 0.489362 (-5960 2035);
WIRE 16 -1 (-6275 1675)(-6275 2025);
WIRE 16 -1 (-6275 2025)(-6775 2025);
WIRE 16 -1 (-6775 2175)(-6475 2175);
WIRE 16 -1 (-6475 2175)(-5025 2175);
FORCEPROP 2 LAST SIG_NAME VSENSE_PVDD18_S5_P0_DN
J 2
(-5460 2185);
DISPLAY 0.489362 (-5460 2185);
WIRE 16 -1 (-6475 1675)(-6475 2175);
WIRE 16 -1 (-5025 2225)(-6550 2225);
FORCEPROP 2 LAST SIG_NAME VSENSE_VSS_SENSE_C_P0
J 2
(-5485 2235);
DISPLAY 0.489362 (-5485 2235);
WIRE 16 -1 (-6550 2225)(-6775 2225);
WIRE 16 -1 (-6550 1675)(-6550 2225);
WIRE 16 -1 (-5025 2275)(-6625 2275);
FORCEPROP 2 LAST SIG_NAME VSENSE_VSS_SENSE_B_P0
J 0
(-5975 2285);
DISPLAY 0.489362 (-5975 2285);
WIRE 16 -1 (-6625 2275)(-6775 2275);
WIRE 16 -1 (-6625 1675)(-6625 2275);
WIRE 16 -1 (-3525 1475)(-2475 1475);
FORCEPROP 2 LAST SIG_NAME UART_CPU0_UART0_R_TX
J 0
(-3285 1485);
DISPLAY 0.489362 (-3285 1485);
FORCEPROP 2 LASTPROP $XRERR UNIQUE?
J 0
(-3525 1485);
DISPLAY 0.638298 (-3525 1485);
PAINT MONO (-3525 1485);
DISPLAY INVISIBLE (-3525 1485);
WIRE 16 -1 (-3525 1325)(-1450 1325);
FORCEPROP 2 LAST SIG_NAME UART_CPU0_SCM_UART1_RX
J 0
(-2150 1335);
DISPLAY 0.489362 (-2150 1335);
WIRE 16 -1 (-725 650)(-1200 650);
FORCEPROP 2 LAST SIG_NAME CPU1_XTRIG_L7
J 0
(-1110 660);
DISPLAY 0.489362 (-1110 660);
WIRE 16 -1 (-1575 2800)(-2050 2800);
FORCEPROP 2 LAST SIG_NAME CPU0_XTRIG_L7
J 0
(-1960 2810);
DISPLAY 0.489362 (-1960 2810);
WIRE 16 -1 (-1575 2850)(-2050 2850);
FORCEPROP 2 LAST SIG_NAME CPU0_XTRIG_L6
J 0
(-1960 2860);
DISPLAY 0.489362 (-1960 2860);
WIRE 16 -1 (-1575 2900)(-2050 2900);
FORCEPROP 2 LAST SIG_NAME CPU0_XTRIG_L5
J 0
(-1960 2910);
DISPLAY 0.489362 (-1960 2910);
WIRE 16 -1 (-475 5600)(-225 5600);
WIRE 16 -1 (-225 5875)(-225 5600);
WIRE 16 -1 (-225 5550)(-225 5600);
WIRE 16 -1 (-225 5500)(-225 5550);
WIRE 16 -1 (-475 5550)(-225 5550);
WIRE 16 -1 (-225 5450)(-225 5500);
WIRE 16 -1 (-475 5500)(-225 5500);
WIRE 16 -1 (-225 5400)(-225 5450);
WIRE 16 -1 (-475 5450)(-225 5450);
WIRE 16 -1 (-225 5350)(-225 5400);
WIRE 16 -1 (-475 5400)(-225 5400);
WIRE 16 -1 (-225 5300)(-225 5350);
WIRE 16 -1 (-475 5350)(-225 5350);
WIRE 16 -1 (-225 5250)(-225 5300);
WIRE 16 -1 (-475 5300)(-225 5300);
WIRE 16 -1 (-225 5200)(-225 5250);
WIRE 16 -1 (-475 5250)(-225 5250);
WIRE 16 -1 (-225 5150)(-225 5200);
WIRE 16 -1 (-475 5200)(-225 5200);
WIRE 16 -1 (-475 5150)(-225 5150);
WIRE 16 -1 (-225 5100)(-225 5150);
WIRE 16 -1 (-475 5100)(-225 5100);
WIRE 16 -1 (-8000 1475)(-7675 1475);
WIRE 16 -1 (-8000 1525)(-8000 1475);
WIRE 16 -1 (-8000 1475)(-8000 1400);
WIRE 16 -1 (-7675 1475)(-7350 1475);
WIRE 16 -1 (-7675 1400)(-7675 1475);
WIRE 16 -1 (-7350 1475)(-7025 1475);
WIRE 16 -1 (-7350 1400)(-7350 1475);
WIRE 16 -1 (-7025 1475)(-6675 1475);
WIRE 16 -1 (-7025 1400)(-7025 1475);
WIRE 16 -1 (-6675 1475)(-6375 1475);
WIRE 16 -1 (-6675 1475)(-6675 1400);
WIRE 16 -1 (-6375 1475)(-6375 1400);
WIRE 16 -1 (-225 2950)(-150 2950);
WIRE 16 -1 (-150 2950)(-150 2900);
WIRE 16 -1 (-150 2900)(-150 2850);
WIRE 16 -1 (-225 2900)(-150 2900);
WIRE 16 -1 (-225 2850)(-150 2850);
WIRE 16 -1 (-150 2850)(-150 2800);
WIRE 16 -1 (-225 2800)(-150 2800);
WIRE 16 -1 (-150 2800)(-150 2700);
WIRE 16 -1 (-225 2325)(-150 2325);
WIRE 16 -1 (-150 2325)(-150 2275);
WIRE 16 -1 (-150 2275)(-150 2225);
WIRE 16 -1 (-225 2275)(-150 2275);
WIRE 16 -1 (-225 2225)(-150 2225);
WIRE 16 -1 (-150 2225)(-150 2175);
WIRE 16 -1 (-225 2175)(-150 2175);
WIRE 16 -1 (-150 2175)(-150 2075);
WIRE 16 -1 (-8800 3150)(-9050 3150);
WIRE 16 -1 (-9050 3350)(-9050 3150);
WIRE 16 -1 (-9050 3100)(-9050 3150);
WIRE 16 -1 (-8800 3100)(-9050 3100);
WIRE 16 -1 (-9050 3050)(-9050 3100);
WIRE 16 -1 (-8800 3050)(-9050 3050);
WIRE 16 -1 (-9050 3000)(-9050 3050);
WIRE 16 -1 (-8800 3000)(-9050 3000);
WIRE 16 -1 (-9050 2950)(-9050 3000);
WIRE 16 -1 (-8800 2950)(-9050 2950);
WIRE 16 -1 (-9050 2900)(-9050 2950);
WIRE 16 -1 (-8800 2900)(-9050 2900);
WIRE 16 -1 (-9050 2850)(-9050 2900);
WIRE 16 -1 (-8800 2850)(-9050 2850);
WIRE 16 -1 (-1375 2800)(-775 2800);
FORCEPROP 2 LAST SIG_NAME CPU0_XTRIG_R1_L7
J 0
(-1235 2810);
DISPLAY 0.489362 (-1235 2810);
FORCEPROP 2 LASTPROP $XRERR UNIQUE?
J 0
(-1475 2810);
DISPLAY 0.638298 (-1475 2810);
PAINT MONO (-1475 2810);
DISPLAY INVISIBLE (-1475 2810);
WIRE 16 -1 (-3525 3825)(-2750 3825);
FORCEPROP 2 LAST SIG_NAME TP_CPU0_TEST6_CCD1
J 0
(-3290 3835);
DISPLAY 0.489362 (-3290 3835);
FORCEPROP 2 LASTPROP $XRERR UNIQUE?
J 0
(-2720 3825);
DISPLAY 0.638298 (-2720 3825);
PAINT MONO (-2720 3825);
DISPLAY INVISIBLE (-2720 3825);
WIRE 16 -1 (-3525 3725)(-2750 3725);
FORCEPROP 2 LAST SIG_NAME TP_CPU0_TEST6_CCD3
J 0
(-3290 3735);
DISPLAY 0.489362 (-3290 3735);
FORCEPROP 2 LASTPROP $XRERR UNIQUE?
J 0
(-2720 3725);
DISPLAY 0.638298 (-2720 3725);
PAINT MONO (-2720 3725);
DISPLAY INVISIBLE (-2720 3725);
WIRE 16 -1 (-2625 4725)(-2025 4725);
FORCEPROP 2 LAST SIG_NAME CPU0_THERMTRIP_R_N
J 0
(-2500 4735);
DISPLAY 0.489362 (-2500 4735);
WIRE 16 -1 (-3525 4425)(-2825 4425);
FORCEPROP 2 LAST SIG_NAME CPU0_XTRIG_R2_L7
J 0
(-3325 4435);
DISPLAY 0.489362 (-3325 4435);
FORCEPROP 2 LASTPROP $XRERR UNIQUE?
J 0
(-3565 4435);
DISPLAY 0.638298 (-3565 4435);
PAINT MONO (-3565 4435);
DISPLAY INVISIBLE (-3565 4435);
WIRE 16 -1 (-6075 4425)(-5025 4425);
FORCEPROP 2 LAST SIG_NAME JTAG_CPU0_TCK
J 0
(-5910 4435);
DISPLAY 0.489362 (-5910 4435);
WIRE 16 -1 (-6075 4475)(-5025 4475);
FORCEPROP 2 LAST SIG_NAME JTAG_CPU0_TRST_N
J 0
(-5910 4485);
DISPLAY 0.489362 (-5910 4485);
WIRE 16 -1 (-1375 2950)(-775 2950);
FORCEPROP 2 LAST SIG_NAME CPU0_XTRIG_R1_L4
J 0
(-1235 2960);
DISPLAY 0.489362 (-1235 2960);
FORCEPROP 2 LASTPROP $XRERR UNIQUE?
J 0
(-1475 2960);
DISPLAY 0.638298 (-1475 2960);
PAINT MONO (-1475 2960);
DISPLAY INVISIBLE (-1475 2960);
WIRE 16 -1 (-1200 2325)(-775 2325);
FORCEPROP 2 LAST SIG_NAME CPU0_BP0
J 0
(-1185 2335);
DISPLAY 0.489362 (-1185 2335);
WIRE 16 -1 (-3525 2625)(-2750 2625);
FORCEPROP 2 LAST SIG_NAME TP_CPU0_TEST4_CCD10
J 0
(-3290 2635);
DISPLAY 0.489362 (-3290 2635);
FORCEPROP 2 LASTPROP $XRERR UNIQUE?
J 0
(-2720 2625);
DISPLAY 0.638298 (-2720 2625);
PAINT MONO (-2720 2625);
DISPLAY INVISIBLE (-2720 2625);
WIRE 16 -1 (-3525 2175)(-2750 2175);
FORCEPROP 2 LAST SIG_NAME TP_CPU0_TEST5_CCD6
J 0
(-3290 2185);
DISPLAY 0.489362 (-3290 2185);
FORCEPROP 2 LASTPROP $XRERR UNIQUE?
J 0
(-2720 2175);
DISPLAY 0.638298 (-2720 2175);
PAINT MONO (-2720 2175);
DISPLAY INVISIBLE (-2720 2175);
WIRE 16 -1 (-1750 750)(-2225 750);
FORCEPROP 2 LAST SIG_NAME CPU0_XTRIG_L6
J 0
(-2135 760);
DISPLAY 0.489362 (-2135 760);
WIRE 16 -1 (-3525 2725)(-2750 2725);
FORCEPROP 2 LAST SIG_NAME TP_CPU0_TEST4_CCD8
J 0
(-3290 2735);
DISPLAY 0.489362 (-3290 2735);
FORCEPROP 2 LASTPROP $XRERR UNIQUE?
J 0
(-2720 2725);
DISPLAY 0.638298 (-2720 2725);
PAINT MONO (-2720 2725);
DISPLAY INVISIBLE (-2720 2725);
WIRE 16 -1 (-1200 2175)(-775 2175);
FORCEPROP 2 LAST SIG_NAME CPU0_BP3
J 0
(-1185 2185);
DISPLAY 0.489362 (-1185 2185);
WIRE 16 -1 (-1200 2225)(-775 2225);
FORCEPROP 2 LAST SIG_NAME CPU0_BP2
J 0
(-1185 2235);
DISPLAY 0.489362 (-1185 2235);
WIRE 16 -1 (-1200 2275)(-775 2275);
FORCEPROP 2 LAST SIG_NAME CPU0_BP1
J 0
(-1185 2285);
DISPLAY 0.489362 (-1185 2285);
WIRE 16 -1 (-1575 2950)(-2050 2950);
FORCEPROP 2 LAST SIG_NAME CPU0_XTRIG_L4
J 0
(-1960 2960);
DISPLAY 0.489362 (-1960 2960);
WIRE 16 -1 (-1375 2900)(-775 2900);
FORCEPROP 2 LAST SIG_NAME CPU0_XTRIG_R1_L5
J 0
(-1235 2910);
DISPLAY 0.489362 (-1235 2910);
FORCEPROP 2 LASTPROP $XRERR UNIQUE?
J 0
(-1475 2910);
DISPLAY 0.638298 (-1475 2910);
PAINT MONO (-1475 2910);
DISPLAY INVISIBLE (-1475 2910);
WIRE 16 -1 (-1375 2850)(-775 2850);
FORCEPROP 2 LAST SIG_NAME CPU0_XTRIG_R1_L6
J 0
(-1235 2860);
DISPLAY 0.489362 (-1235 2860);
FORCEPROP 2 LASTPROP $XRERR UNIQUE?
J 0
(-1475 2860);
DISPLAY 0.638298 (-1475 2860);
PAINT MONO (-1475 2860);
DISPLAY INVISIBLE (-1475 2860);
WIRE 16 -1 (-3525 1425)(-1450 1425);
FORCEPROP 2 LAST SIG_NAME UART_CPU0_UART0_RX
J 0
(-2150 1435);
DISPLAY 0.489362 (-2150 1435);
WIRE 16 -1 (-3525 1825)(-2750 1825);
FORCEPROP 2 LAST SIG_NAME TP_CPU0_TEST4_IOD
J 0
(-3290 1835);
DISPLAY 0.489362 (-3290 1835);
FORCEPROP 2 LASTPROP $XRERR UNIQUE?
J 0
(-2720 1825);
DISPLAY 0.638298 (-2720 1825);
PAINT MONO (-2720 1825);
DISPLAY INVISIBLE (-2720 1825);
WIRE 16 -1 (-3525 1925)(-2750 1925);
FORCEPROP 2 LAST SIG_NAME TP_CPU0_TEST5_CCD11
J 0
(-3290 1935);
DISPLAY 0.489362 (-3290 1935);
FORCEPROP 2 LASTPROP $XRERR UNIQUE?
J 0
(-2720 1925);
DISPLAY 0.638298 (-2720 1925);
PAINT MONO (-2720 1925);
DISPLAY INVISIBLE (-2720 1925);
WIRE 16 -1 (-3525 3225)(-2750 3225);
FORCEPROP 2 LAST SIG_NAME TP_CPU0_TEST6_IOD
J 0
(-3290 3235);
DISPLAY 0.489362 (-3290 3235);
FORCEPROP 2 LASTPROP $XRERR UNIQUE?
J 0
(-2720 3225);
DISPLAY 0.638298 (-2720 3225);
PAINT MONO (-2720 3225);
DISPLAY INVISIBLE (-2720 3225);
WIRE 16 -1 (-3525 3325)(-2750 3325);
FORCEPROP 2 LAST SIG_NAME TP_CPU0_TEST6_X3D5
J 0
(-3290 3335);
DISPLAY 0.489362 (-3290 3335);
FORCEPROP 2 LASTPROP $XRERR UNIQUE?
J 0
(-2720 3325);
DISPLAY 0.638298 (-2720 3325);
PAINT MONO (-2720 3325);
DISPLAY INVISIBLE (-2720 3325);
WIRE 16 -1 (-5025 3825)(-6125 3825);
FORCEPROP 2 LAST SIG_NAME TP_CPU0_TEST47_CCD0
J 0
(-5885 3835);
DISPLAY 0.489362 (-5885 3835);
FORCEPROP 2 LASTPROP $XRERR UNIQUE?
J 0
(-6365 3825);
DISPLAY 0.638298 (-6365 3825);
PAINT MONO (-6365 3825);
DISPLAY INVISIBLE (-6365 3825);
WIRE 16 -1 (-3525 4725)(-2825 4725);
FORCEPROP 2 LAST SIG_NAME CPU0_THERMTRIP_N
J 0
(-3325 4735);
DISPLAY 0.489362 (-3325 4735);
FORCEPROP 2 LASTPROP $XR0 27 
J 0
(-3390 4735);
DISPLAY 0.638298 (-3390 4735);
PAINT MONO (-3390 4735);
WIRE 16 -1 (-3525 4875)(-2825 4875);
FORCEPROP 2 LAST SIG_NAME APML_CPU0_ALERT_N
J 0
(-3325 4885);
DISPLAY 0.489362 (-3325 4885);
FORCEPROP 2 LASTPROP $XR0 27 
J 0
(-3390 4885);
DISPLAY 0.638298 (-3390 4885);
PAINT MONO (-3390 4885);
WIRE 16 -1 (-2625 4875)(-2025 4875);
FORCEPROP 2 LAST SIG_NAME APML_CPU0_ALERT_R_N
J 0
(-2475 4885);
DISPLAY 0.489362 (-2475 4885);
WIRE 16 -1 (-8725 1050)(-7675 1050);
FORCEPROP 2 LAST SIG_NAME JTAG_CPU0_TDI
J 0
(-8560 1060);
DISPLAY 0.489362 (-8560 1060);
WIRE 16 -1 (-7675 1200)(-7675 1050);
WIRE 16 -1 (-7675 700)(-7675 1050);
WIRE 16 -1 (-8725 1000)(-7350 1000);
FORCEPROP 2 LAST SIG_NAME JTAG_CPU0_TRST_N
J 0
(-8560 1010);
DISPLAY 0.489362 (-8560 1010);
WIRE 16 -1 (-7350 1200)(-7350 1000);
WIRE 16 -1 (-7350 700)(-7350 1000);
WIRE 16 -1 (-8725 950)(-7025 950);
FORCEPROP 2 LAST SIG_NAME JTAG_CPU0_TCK
J 0
(-8560 960);
DISPLAY 0.489362 (-8560 960);
WIRE 16 -1 (-7025 1200)(-7025 950);
WIRE 16 -1 (-7025 700)(-7025 950);
WIRE 16 -1 (-8725 900)(-6675 900);
FORCEPROP 2 LAST SIG_NAME JTAG_CPU0_TMS
J 0
(-8560 910);
DISPLAY 0.489362 (-8560 910);
WIRE 16 -1 (-6675 1200)(-6675 900);
WIRE 16 -1 (-6675 700)(-6675 900);
WIRE 16 -1 (-8725 850)(-6375 850);
FORCEPROP 2 LAST SIG_NAME JTAG_CPU0_DBREQ_N
J 0
(-8560 860);
DISPLAY 0.489362 (-8560 860);
WIRE 16 -1 (-6375 850)(-6375 1200);
WIRE 16 -1 (-6375 700)(-6375 850);
WIRE 16 -1 (-8725 1100)(-8000 1100);
FORCEPROP 2 LAST SIG_NAME JTAG_CPU0_TDO
J 0
(-8560 1110);
DISPLAY 0.489362 (-8560 1110);
WIRE 16 -1 (-8000 1200)(-8000 1100);
WIRE 16 -1 (-8000 700)(-8000 1100);
WIRE 16 -1 (-1450 1375)(-2275 1375);
FORCEPROP 2 LAST SIG_NAME UART_CPU0_SCM_UART1_TX
J 0
(-2150 1385);
DISPLAY 0.489362 (-2150 1385);
WIRE 16 -1 (-3525 1625)(-2600 1625);
FORCEPROP 2 LAST SIG_NAME FM_BIOS_USB_RECOVERY_R
J 0
(-3385 1635);
DISPLAY 0.489362 (-3385 1635);
FORCEPROP 2 LASTPROP $XRERR UNIQUE?
J 0
(-3625 1635);
DISPLAY 0.638298 (-3625 1635);
PAINT MONO (-3625 1635);
DISPLAY INVISIBLE (-3625 1635);
WIRE 16 -1 (-3525 4475)(-2825 4475);
FORCEPROP 2 LAST SIG_NAME CPU0_XTRIG_R2_L6
J 0
(-3325 4485);
DISPLAY 0.489362 (-3325 4485);
FORCEPROP 2 LASTPROP $XRERR UNIQUE?
J 0
(-3565 4485);
DISPLAY 0.638298 (-3565 4485);
PAINT MONO (-3565 4485);
DISPLAY INVISIBLE (-3565 4485);
WIRE 16 -1 (-2625 4475)(-2025 4475);
FORCEPROP 2 LAST SIG_NAME CPU0_XTRIG_L6
J 0
(-2425 4485);
DISPLAY 0.489362 (-2425 4485);
WIRE 16 -1 (-2625 4425)(-2025 4425);
FORCEPROP 2 LAST SIG_NAME CPU0_XTRIG_L7
J 0
(-2425 4435);
DISPLAY 0.489362 (-2425 4435);
WIRE 16 -1 (-3525 4525)(-2825 4525);
FORCEPROP 2 LAST SIG_NAME CPU0_XTRIG_R2_L5
J 0
(-3325 4535);
DISPLAY 0.489362 (-3325 4535);
FORCEPROP 2 LASTPROP $XRERR UNIQUE?
J 0
(-3565 4535);
DISPLAY 0.638298 (-3565 4535);
PAINT MONO (-3565 4535);
DISPLAY INVISIBLE (-3565 4535);
WIRE 16 -1 (-2625 4525)(-2025 4525);
FORCEPROP 2 LAST SIG_NAME CPU0_XTRIG_L5
J 0
(-2425 4535);
DISPLAY 0.489362 (-2425 4535);
WIRE 16 -1 (-3525 4575)(-2825 4575);
FORCEPROP 2 LAST SIG_NAME CPU0_XTRIG_R2_L4
J 0
(-3325 4585);
DISPLAY 0.489362 (-3325 4585);
FORCEPROP 2 LASTPROP $XRERR UNIQUE?
J 0
(-3565 4585);
DISPLAY 0.638298 (-3565 4585);
PAINT MONO (-3565 4585);
DISPLAY INVISIBLE (-3565 4585);
WIRE 16 -1 (-2625 4575)(-2025 4575);
FORCEPROP 2 LAST SIG_NAME CPU0_XTRIG_L4
J 0
(-2425 4585);
DISPLAY 0.489362 (-2425 4585);
WIRE 16 -1 (-5025 4575)(-5625 4575);
FORCEPROP 2 LAST SIG_NAME JTAG_CPU0_R_TDO
J 0
(-5560 4585);
DISPLAY 0.489362 (-5560 4585);
FORCEPROP 2 LASTPROP $XRERR UNIQUE?
J 0
(-5800 4585);
DISPLAY 0.638298 (-5800 4585);
PAINT MONO (-5800 4585);
DISPLAY INVISIBLE (-5800 4585);
WIRE 16 -1 (-6525 4575)(-5825 4575);
FORCEPROP 2 LAST SIG_NAME JTAG_CPU0_TDO
J 0
(-6435 4585);
DISPLAY 0.489362 (-6435 4585);
WIRE 16 -1 (-5025 2775)(-6075 2775);
FORCEPROP 2 LAST SIG_NAME CPU0_SP5R1
J 2
(-5735 2785);
DISPLAY 0.489362 (-5735 2785);
WIRE 16 -1 (-6075 2725)(-5025 2725);
FORCEPROP 2 LAST SIG_NAME CPU0_SP5R2
J 2
(-5735 2735);
DISPLAY 0.489362 (-5735 2735);
WIRE 16 -1 (-5025 2975)(-6075 2975);
FORCEPROP 2 LAST SIG_NAME CPU0_SA0
J 0
(-5960 2985);
DISPLAY 0.489362 (-5960 2985);
WIRE 16 -1 (-5025 4275)(-6075 4275);
FORCEPROP 2 LAST SIG_NAME JTAG_CPU0_DBREQ_N
J 0
(-5910 4285);
DISPLAY 0.489362 (-5910 4285);
WIRE 16 -1 (-6075 4375)(-5025 4375);
FORCEPROP 2 LAST SIG_NAME JTAG_CPU0_TMS
J 0
(-5910 4385);
DISPLAY 0.489362 (-5910 4385);
WIRE 16 -1 (-675 5150)(-1475 5150);
FORCEPROP 2 LAST SIG_NAME CPU0_THERMTRIP_N
J 0
(-1450 5160);
DISPLAY 0.489362 (-1450 5160);
WIRE 16 -1 (-675 5200)(-1475 5200);
FORCEPROP 2 LAST SIG_NAME CPU0_XTRIG_L7
J 0
(-1450 5210);
DISPLAY 0.489362 (-1450 5210);
WIRE 16 -1 (-675 5250)(-1475 5250);
FORCEPROP 2 LAST SIG_NAME CPU0_XTRIG_L6
J 0
(-1450 5260);
DISPLAY 0.489362 (-1450 5260);
WIRE 16 -1 (-675 5350)(-1475 5350);
FORCEPROP 2 LAST SIG_NAME CPU0_XTRIG_L4
J 0
(-1450 5360);
DISPLAY 0.489362 (-1450 5360);
WIRE 16 -1 (-675 5300)(-1475 5300);
FORCEPROP 2 LAST SIG_NAME CPU0_XTRIG_L5
J 0
(-1450 5310);
DISPLAY 0.489362 (-1450 5310);
WIRE 16 -1 (-675 5450)(-1475 5450);
FORCEPROP 2 LAST SIG_NAME CPU0_BP3
J 0
(-1450 5460);
DISPLAY 0.489362 (-1450 5460);
WIRE 16 -1 (-675 5500)(-1475 5500);
FORCEPROP 2 LAST SIG_NAME CPU0_BP2
J 0
(-1450 5510);
DISPLAY 0.489362 (-1450 5510);
WIRE 16 -1 (-675 5600)(-1475 5600);
FORCEPROP 2 LAST SIG_NAME CPU0_BP0
J 0
(-1450 5610);
DISPLAY 0.489362 (-1450 5610);
WIRE 16 -1 (-675 5550)(-1475 5550);
FORCEPROP 2 LAST SIG_NAME CPU0_BP1
J 0
(-1450 5560);
DISPLAY 0.489362 (-1450 5560);
WIRE 16 -1 (-3525 2375)(-2750 2375);
FORCEPROP 2 LAST SIG_NAME TP_CPU0_TEST5_CCD2
J 0
(-3290 2385);
DISPLAY 0.489362 (-3290 2385);
FORCEPROP 2 LASTPROP $XRERR UNIQUE?
J 0
(-2720 2375);
DISPLAY 0.638298 (-2720 2375);
PAINT MONO (-2720 2375);
DISPLAY INVISIBLE (-2720 2375);
WIRE 16 -1 (-3525 3475)(-2750 3475);
FORCEPROP 2 LAST SIG_NAME TP_CPU0_TEST6_X3D2
J 0
(-3290 3485);
DISPLAY 0.489362 (-3290 3485);
FORCEPROP 2 LASTPROP $XRERR UNIQUE?
J 0
(-2720 3475);
DISPLAY 0.638298 (-2720 3475);
PAINT MONO (-2720 3475);
DISPLAY INVISIBLE (-2720 3475);
WIRE 16 -1 (-3525 3525)(-2750 3525);
FORCEPROP 2 LAST SIG_NAME TP_CPU0_TEST6_X3D1
J 0
(-3290 3535);
DISPLAY 0.489362 (-3290 3535);
FORCEPROP 2 LASTPROP $XRERR UNIQUE?
J 0
(-2720 3525);
DISPLAY 0.638298 (-2720 3525);
PAINT MONO (-2720 3525);
DISPLAY INVISIBLE (-2720 3525);
WIRE 16 -1 (-3525 3575)(-2750 3575);
FORCEPROP 2 LAST SIG_NAME TP_CPU0_TEST6_X3D0
J 0
(-3290 3585);
DISPLAY 0.489362 (-3290 3585);
FORCEPROP 2 LASTPROP $XRERR UNIQUE?
J 0
(-2720 3575);
DISPLAY 0.638298 (-2720 3575);
PAINT MONO (-2720 3575);
DISPLAY INVISIBLE (-2720 3575);
WIRE 16 -1 (-3525 2675)(-2750 2675);
FORCEPROP 2 LAST SIG_NAME TP_CPU0_TEST4_CCD9
J 0
(-3290 2685);
DISPLAY 0.489362 (-3290 2685);
FORCEPROP 2 LASTPROP $XRERR UNIQUE?
J 0
(-2720 2675);
DISPLAY 0.638298 (-2720 2675);
PAINT MONO (-2720 2675);
DISPLAY INVISIBLE (-2720 2675);
WIRE 16 -1 (-3525 2775)(-2750 2775);
FORCEPROP 2 LAST SIG_NAME TP_CPU0_TEST4_CCD7
J 0
(-3290 2785);
DISPLAY 0.489362 (-3290 2785);
FORCEPROP 2 LASTPROP $XRERR UNIQUE?
J 0
(-2720 2775);
DISPLAY 0.638298 (-2720 2775);
PAINT MONO (-2720 2775);
DISPLAY INVISIBLE (-2720 2775);
WIRE 16 -1 (-3525 2825)(-2750 2825);
FORCEPROP 2 LAST SIG_NAME TP_CPU0_TEST4_CCD6
J 0
(-3290 2835);
DISPLAY 0.489362 (-3290 2835);
FORCEPROP 2 LASTPROP $XRERR UNIQUE?
J 0
(-2720 2825);
DISPLAY 0.638298 (-2720 2825);
PAINT MONO (-2720 2825);
DISPLAY INVISIBLE (-2720 2825);
WIRE 16 -1 (-3525 2875)(-2750 2875);
FORCEPROP 2 LAST SIG_NAME TP_CPU0_TEST4_CCD5
J 0
(-3290 2885);
DISPLAY 0.489362 (-3290 2885);
FORCEPROP 2 LASTPROP $XRERR UNIQUE?
J 0
(-2720 2875);
DISPLAY 0.638298 (-2720 2875);
PAINT MONO (-2720 2875);
DISPLAY INVISIBLE (-2720 2875);
WIRE 16 -1 (-3525 2925)(-2750 2925);
FORCEPROP 2 LAST SIG_NAME TP_CPU0_TEST4_CCD4
J 0
(-3290 2935);
DISPLAY 0.489362 (-3290 2935);
FORCEPROP 2 LASTPROP $XRERR UNIQUE?
J 0
(-2720 2925);
DISPLAY 0.638298 (-2720 2925);
PAINT MONO (-2720 2925);
DISPLAY INVISIBLE (-2720 2925);
WIRE 16 -1 (-3525 2975)(-2750 2975);
FORCEPROP 2 LAST SIG_NAME TP_CPU0_TEST4_CCD3
J 0
(-3290 2985);
DISPLAY 0.489362 (-3290 2985);
FORCEPROP 2 LASTPROP $XRERR UNIQUE?
J 0
(-2720 2975);
DISPLAY 0.638298 (-2720 2975);
PAINT MONO (-2720 2975);
DISPLAY INVISIBLE (-2720 2975);
WIRE 16 -1 (-3525 2275)(-2750 2275);
FORCEPROP 2 LAST SIG_NAME TP_CPU0_TEST5_CCD4
J 0
(-3290 2285);
DISPLAY 0.489362 (-3290 2285);
FORCEPROP 2 LASTPROP $XRERR UNIQUE?
J 0
(-2720 2275);
DISPLAY 0.638298 (-2720 2275);
PAINT MONO (-2720 2275);
DISPLAY INVISIBLE (-2720 2275);
WIRE 16 -1 (-3525 3025)(-2750 3025);
FORCEPROP 2 LAST SIG_NAME TP_CPU0_TEST4_CCD2
J 0
(-3290 3035);
DISPLAY 0.489362 (-3290 3035);
FORCEPROP 2 LASTPROP $XRERR UNIQUE?
J 0
(-2720 3025);
DISPLAY 0.638298 (-2720 3025);
PAINT MONO (-2720 3025);
DISPLAY INVISIBLE (-2720 3025);
WIRE 16 -1 (-3525 2325)(-2750 2325);
FORCEPROP 2 LAST SIG_NAME TP_CPU0_TEST5_CCD3
J 0
(-3290 2335);
DISPLAY 0.489362 (-3290 2335);
FORCEPROP 2 LASTPROP $XRERR UNIQUE?
J 0
(-2720 2325);
DISPLAY 0.638298 (-2720 2325);
PAINT MONO (-2720 2325);
DISPLAY INVISIBLE (-2720 2325);
WIRE 16 -1 (-3525 3075)(-2750 3075);
FORCEPROP 2 LAST SIG_NAME TP_CPU0_TEST4_CCD1
J 0
(-3290 3085);
DISPLAY 0.489362 (-3290 3085);
FORCEPROP 2 LASTPROP $XRERR UNIQUE?
J 0
(-2720 3075);
DISPLAY 0.638298 (-2720 3075);
PAINT MONO (-2720 3075);
DISPLAY INVISIBLE (-2720 3075);
WIRE 16 -1 (-3525 3125)(-2750 3125);
FORCEPROP 2 LAST SIG_NAME TP_CPU0_TEST4_CCD0
J 0
(-3290 3135);
DISPLAY 0.489362 (-3290 3135);
FORCEPROP 2 LASTPROP $XRERR UNIQUE?
J 0
(-2720 3125);
DISPLAY 0.638298 (-2720 3125);
PAINT MONO (-2720 3125);
DISPLAY INVISIBLE (-2720 3125);
WIRE 16 -1 (-3525 3375)(-2750 3375);
FORCEPROP 2 LAST SIG_NAME TP_CPU0_TEST6_X3D4
J 0
(-3290 3385);
DISPLAY 0.489362 (-3290 3385);
FORCEPROP 2 LASTPROP $XRERR UNIQUE?
J 0
(-2720 3375);
DISPLAY 0.638298 (-2720 3375);
PAINT MONO (-2720 3375);
DISPLAY INVISIBLE (-2720 3375);
WIRE 16 -1 (-3525 1975)(-2750 1975);
FORCEPROP 2 LAST SIG_NAME TP_CPU0_TEST5_CCD10
J 0
(-3290 1985);
DISPLAY 0.489362 (-3290 1985);
FORCEPROP 2 LASTPROP $XRERR UNIQUE?
J 0
(-2720 1975);
DISPLAY 0.638298 (-2720 1975);
PAINT MONO (-2720 1975);
DISPLAY INVISIBLE (-2720 1975);
WIRE 16 -1 (-3525 2025)(-2750 2025);
FORCEPROP 2 LAST SIG_NAME TP_CPU0_TEST5_CCD9
J 0
(-3290 2035);
DISPLAY 0.489362 (-3290 2035);
FORCEPROP 2 LASTPROP $XRERR UNIQUE?
J 0
(-2720 2025);
DISPLAY 0.638298 (-2720 2025);
PAINT MONO (-2720 2025);
DISPLAY INVISIBLE (-2720 2025);
WIRE 16 -1 (-5025 2925)(-6075 2925);
FORCEPROP 2 LAST SIG_NAME CPU0_SA1
J 0
(-5960 2935);
DISPLAY 0.489362 (-5960 2935);
WIRE 16 -1 (-6075 2625)(-5025 2625);
FORCEPROP 2 LAST SIG_NAME CPU0_SP5R4
J 2
(-5735 2635);
DISPLAY 0.489362 (-5735 2635);
WIRE 16 -1 (-5025 2675)(-6075 2675);
FORCEPROP 2 LAST SIG_NAME CPU0_SP5R3
J 2
(-5735 2685);
DISPLAY 0.489362 (-5735 2685);
WIRE 16 -1 (-6075 2475)(-5025 2475);
FORCEPROP 2 LAST SIG_NAME CPU0_CORETYPE1
J 2
(-5635 2485);
DISPLAY 0.489362 (-5635 2485);
WIRE 16 -1 (-5025 2525)(-6075 2525);
FORCEPROP 2 LAST SIG_NAME CPU0_CORETYPE0
J 2
(-5635 2535);
DISPLAY 0.489362 (-5635 2535);
WIRE 16 -1 (-5025 2425)(-6075 2425);
FORCEPROP 2 LAST SIG_NAME CPU0_CORETYPE2
J 2
(-5635 2435);
DISPLAY 0.489362 (-5635 2435);
WIRE 16 -1 (-5025 3725)(-6125 3725);
FORCEPROP 2 LAST SIG_NAME TP_CPU0_TEST47_CCD2
J 0
(-5885 3735);
DISPLAY 0.489362 (-5885 3735);
FORCEPROP 2 LASTPROP $XRERR UNIQUE?
J 0
(-6365 3725);
DISPLAY 0.638298 (-6365 3725);
PAINT MONO (-6365 3725);
DISPLAY INVISIBLE (-6365 3725);
WIRE 16 -1 (-8600 3000)(-7775 3000);
FORCEPROP 2 LAST SIG_NAME CPU0_SP5R4
J 0
(-8275 3010);
DISPLAY 0.489362 (-8275 3010);
WIRE 16 -1 (-8600 3050)(-7775 3050);
FORCEPROP 2 LAST SIG_NAME CPU0_SP5R3
J 0
(-8275 3060);
DISPLAY 0.489362 (-8275 3060);
WIRE 16 -1 (-8600 3150)(-7775 3150);
FORCEPROP 2 LAST SIG_NAME CPU0_SP5R1
J 0
(-8275 3160);
DISPLAY 0.489362 (-8275 3160);
WIRE 16 -1 (-8600 3100)(-7775 3100);
FORCEPROP 2 LAST SIG_NAME CPU0_SP5R2
J 0
(-8275 3110);
DISPLAY 0.489362 (-8275 3110);
WIRE 16 -1 (-7775 2850)(-8600 2850);
FORCEPROP 2 LAST SIG_NAME CPU0_CORETYPE2
J 0
(-8275 2860);
DISPLAY 0.489362 (-8275 2860);
WIRE 16 -1 (-8600 2900)(-7775 2900);
FORCEPROP 2 LAST SIG_NAME CPU0_CORETYPE1
J 0
(-8275 2910);
DISPLAY 0.489362 (-8275 2910);
WIRE 16 -1 (-8600 2950)(-7775 2950);
FORCEPROP 2 LAST SIG_NAME CPU0_CORETYPE0
J 0
(-8275 2960);
DISPLAY 0.489362 (-8275 2960);
WIRE 16 -1 (-3525 5775)(-2750 5775);
FORCEPROP 2 LAST SIG_NAME NC_CPU0_AZ_BITCLK
J 0
(-3315 5785);
DISPLAY 0.489362 (-3315 5785);
FORCEPROP 2 LASTPROP $XRERR UNIQUE?
J 0
(-2720 5775);
DISPLAY 0.638298 (-2720 5775);
PAINT MONO (-2720 5775);
DISPLAY INVISIBLE (-2720 5775);
WIRE 16 -1 (-3525 5725)(-2750 5725);
FORCEPROP 2 LAST SIG_NAME NC_CPU0_AZ_RST_N
J 0
(-3315 5735);
DISPLAY 0.489362 (-3315 5735);
FORCEPROP 2 LASTPROP $XRERR UNIQUE?
J 0
(-2720 5725);
DISPLAY 0.638298 (-2720 5725);
PAINT MONO (-2720 5725);
DISPLAY INVISIBLE (-2720 5725);
WIRE 16 -1 (-3525 5675)(-2750 5675);
FORCEPROP 2 LAST SIG_NAME NC_CPU0_AZ_SDIN0
J 0
(-3315 5685);
DISPLAY 0.489362 (-3315 5685);
FORCEPROP 2 LASTPROP $XRERR UNIQUE?
J 0
(-2720 5675);
DISPLAY 0.638298 (-2720 5675);
PAINT MONO (-2720 5675);
DISPLAY INVISIBLE (-2720 5675);
WIRE 16 -1 (-3525 5625)(-2750 5625);
FORCEPROP 2 LAST SIG_NAME NC_CPU0_AZ_SDIN1
J 0
(-3315 5635);
DISPLAY 0.489362 (-3315 5635);
FORCEPROP 2 LASTPROP $XRERR UNIQUE?
J 0
(-2720 5625);
DISPLAY 0.638298 (-2720 5625);
PAINT MONO (-2720 5625);
DISPLAY INVISIBLE (-2720 5625);
WIRE 16 -1 (-3525 5575)(-2750 5575);
FORCEPROP 2 LAST SIG_NAME NC_CPU0_AZ_SDIN2
J 0
(-3315 5585);
DISPLAY 0.489362 (-3315 5585);
FORCEPROP 2 LASTPROP $XRERR UNIQUE?
J 0
(-2720 5575);
DISPLAY 0.638298 (-2720 5575);
PAINT MONO (-2720 5575);
DISPLAY INVISIBLE (-2720 5575);
WIRE 16 -1 (-3525 5525)(-2750 5525);
FORCEPROP 2 LAST SIG_NAME NC_CPU0_AZ_SDOUT
J 0
(-3315 5535);
DISPLAY 0.489362 (-3315 5535);
FORCEPROP 2 LASTPROP $XRERR UNIQUE?
J 0
(-2720 5525);
DISPLAY 0.638298 (-2720 5525);
PAINT MONO (-2720 5525);
DISPLAY INVISIBLE (-2720 5525);
WIRE 16 -1 (-3525 5475)(-2750 5475);
FORCEPROP 2 LAST SIG_NAME NC_CPU0_AZ_SYNC
J 0
(-3315 5485);
DISPLAY 0.489362 (-3315 5485);
FORCEPROP 2 LASTPROP $XRERR UNIQUE?
J 0
(-2720 5475);
DISPLAY 0.638298 (-2720 5475);
PAINT MONO (-2720 5475);
DISPLAY INVISIBLE (-2720 5475);
WIRE 16 -1 (-5025 3775)(-6125 3775);
FORCEPROP 2 LAST SIG_NAME TP_CPU0_TEST47_CCD1
J 0
(-5885 3785);
DISPLAY 0.489362 (-5885 3785);
FORCEPROP 2 LASTPROP $XRERR UNIQUE?
J 0
(-6365 3775);
DISPLAY 0.638298 (-6365 3775);
PAINT MONO (-6365 3775);
DISPLAY INVISIBLE (-6365 3775);
WIRE 16 -1 (-675 5400)(-1475 5400);
FORCEPROP 2 LAST SIG_NAME CPU0_PROCHOT_N
J 0
(-1450 5410);
DISPLAY 0.489362 (-1450 5410);
WIRE 16 -1 (-3525 4225)(-2700 4225);
FORCEPROP 2 LAST SIG_NAME CPU0_BP0
J 0
(-3310 4235);
DISPLAY 0.489362 (-3310 4235);
WIRE 16 -1 (-3525 3775)(-2750 3775);
FORCEPROP 2 LAST SIG_NAME TP_CPU0_TEST6_CCD2
J 0
(-3290 3785);
DISPLAY 0.489362 (-3290 3785);
FORCEPROP 2 LASTPROP $XRERR UNIQUE?
J 0
(-2720 3775);
DISPLAY 0.638298 (-2720 3775);
PAINT MONO (-2720 3775);
DISPLAY INVISIBLE (-2720 3775);
WIRE 16 -1 (-3525 3875)(-2750 3875);
FORCEPROP 2 LAST SIG_NAME TP_CPU0_TEST6_CCD0
J 0
(-3290 3885);
DISPLAY 0.489362 (-3290 3885);
FORCEPROP 2 LASTPROP $XRERR UNIQUE?
J 0
(-2720 3875);
DISPLAY 0.638298 (-2720 3875);
PAINT MONO (-2720 3875);
DISPLAY INVISIBLE (-2720 3875);
WIRE 16 -1 (-3525 4125)(-2700 4125);
FORCEPROP 2 LAST SIG_NAME CPU0_BP2
J 0
(-3310 4135);
DISPLAY 0.489362 (-3310 4135);
WIRE 16 -1 (-3525 4175)(-2700 4175);
FORCEPROP 2 LAST SIG_NAME CPU0_BP1
J 0
(-3310 4185);
DISPLAY 0.489362 (-3310 4185);
WIRE 16 -1 (-5025 5675)(-5700 5675);
FORCEPROP 2 LAST SIG_NAME FM_P0_PCC0_N
J 0
(-5685 5685);
DISPLAY 0.489362 (-5685 5685);
WIRE 16 -1 (-5025 5625)(-5700 5625);
FORCEPROP 2 LAST SIG_NAME FM_P0_PCC1_N
J 0
(-5685 5635);
DISPLAY 0.489362 (-5685 5635);
WIRE 16 -1 (-8675 4525)(-7825 4525);
FORCEPROP 2 LAST SIG_NAME CPU0_SA0
J 0
(-8310 4535);
DISPLAY 0.489362 (-8310 4535);
WIRE 16 -1 (-8675 4550)(-8675 4525);
WIRE 16 -1 (-8675 4525)(-8675 4450);
WIRE 16 -1 (-5700 5225)(-5025 5225);
FORCEPROP 2 LAST SIG_NAME SVID_PVDDCR_CPU1_P0_SVTO
J 0
(-5685 5235);
DISPLAY 0.489362 (-5685 5235);
WIRE 16 -1 (-675 5100)(-1475 5100);
FORCEPROP 2 LAST SIG_NAME APML_CPU0_ALERT_N
J 0
(-1450 5110);
DISPLAY 0.489362 (-1450 5110);
WIRE 16 -1 (-3525 1125)(-2750 1125);
FORCEPROP 2 LAST SIG_NAME TP_CPU0_TEST41_IDO
J 0
(-3235 1135);
DISPLAY 0.489362 (-3235 1135);
FORCEPROP 2 LASTPROP $XRERR UNIQUE?
J 0
(-2720 1125);
DISPLAY 0.638298 (-2720 1125);
PAINT MONO (-2720 1125);
DISPLAY INVISIBLE (-2720 1125);
WIRE 16 -1 (-5025 1925)(-6125 1925);
FORCEPROP 2 LAST SIG_NAME VSENSE_PVDD11_S3_P0_DP
J 2
(-5460 1935);
DISPLAY 0.489362 (-5460 1935);
WIRE 16 -1 (-6125 1675)(-6125 1925);
WIRE 16 -1 (-6125 1925)(-6775 1925);
WIRE 16 -1 (-5025 4875)(-6075 4875);
FORCEPROP 2 LAST SIG_NAME SMB_APML_CPU0_SCL
J 2
(-5510 4885);
DISPLAY 0.489362 (-5510 4885);
WIRE 16 -1 (-5025 4825)(-6075 4825);
FORCEPROP 2 LAST SIG_NAME SMB_APML_CPU0_SDA
J 2
(-5510 4835);
DISPLAY 0.489362 (-5510 4835);
WIRE 16 -1 (-5025 4525)(-6075 4525);
FORCEPROP 2 LAST SIG_NAME JTAG_CPU0_TDI
J 0
(-5910 4535);
DISPLAY 0.489362 (-5910 4535);
WIRE 16 -1 (-3525 4075)(-2700 4075);
FORCEPROP 2 LAST SIG_NAME CPU0_BP3
J 0
(-3310 4085);
DISPLAY 0.489362 (-3310 4085);
WIRE 16 -1 (-3525 1725)(-2750 1725);
FORCEPROP 2 LAST SIG_NAME TP_CPU0_TEST5_IOD
J 0
(-3290 1735);
DISPLAY 0.489362 (-3290 1735);
FORCEPROP 2 LASTPROP $XRERR UNIQUE?
J 0
(-2720 1725);
DISPLAY 0.638298 (-2720 1725);
PAINT MONO (-2720 1725);
DISPLAY INVISIBLE (-2720 1725);
WIRE 16 -1 (-5025 3225)(-6075 3225);
FORCEPROP 2 LAST SIG_NAME TP_CPU0_TEST50_IOD
J 0
(-5945 3235);
DISPLAY 0.489362 (-5945 3235);
FORCEPROP 2 LASTPROP $XRERR UNIQUE?
J 0
(-6315 3225);
DISPLAY 0.638298 (-6315 3225);
PAINT MONO (-6315 3225);
DISPLAY INVISIBLE (-6315 3225);
WIRE 16 -1 (-5025 3075)(-6075 3075);
FORCEPROP 2 LAST SIG_NAME PRSNT_CPU0_N
J 2
(-5685 3085);
DISPLAY 0.489362 (-5685 3085);
WIRE 16 -1 (-5025 2075)(-6350 2075);
FORCEPROP 2 LAST SIG_NAME VSENSE_PVDDIO_P0_DP
J 0
(-5960 2085);
DISPLAY 0.489362 (-5960 2085);
WIRE 16 -1 (-6350 2075)(-6775 2075);
WIRE 16 -1 (-6350 1675)(-6350 2075);
WIRE 16 -1 (-5025 2325)(-6700 2325);
FORCEPROP 2 LAST SIG_NAME VSENSE_VSS_SENSE_A_P0
J 0
(-5975 2335);
DISPLAY 0.489362 (-5975 2335);
WIRE 16 -1 (-6700 2325)(-6775 2325);
WIRE 16 -1 (-6700 1675)(-6700 2325);
WIRE 16 -1 (-2400 1625)(-1625 1625);
FORCEPROP 2 LAST SIG_NAME FM_BIOS_USB_RECOVERY
J 0
(-2310 1635);
DISPLAY 0.489362 (-2310 1635);
WIRE 16 -1 (-1750 650)(-2225 650);
FORCEPROP 2 LAST SIG_NAME CPU0_XTRIG_L7
J 0
(-2135 660);
DISPLAY 0.489362 (-2135 660);
WIRE 16 -1 (-725 750)(-1200 750);
FORCEPROP 2 LAST SIG_NAME CPU1_XTRIG_L6
J 0
(-1110 760);
DISPLAY 0.489362 (-1110 760);
WIRE 16 -1 (-725 850)(-1200 850);
FORCEPROP 2 LAST SIG_NAME CPU1_XTRIG_L5
J 0
(-1110 860);
DISPLAY 0.489362 (-1110 860);
WIRE 16 -1 (-1750 850)(-2225 850);
FORCEPROP 2 LAST SIG_NAME CPU0_XTRIG_L5
J 0
(-2135 860);
DISPLAY 0.489362 (-2135 860);
WIRE 16 -1 (-725 950)(-1200 950);
FORCEPROP 2 LAST SIG_NAME CPU1_XTRIG_L4
J 0
(-1110 960);
DISPLAY 0.489362 (-1110 960);
WIRE 16 -1 (-1750 950)(-2225 950);
FORCEPROP 2 LAST SIG_NAME CPU0_XTRIG_L4
J 0
(-2135 960);
DISPLAY 0.489362 (-2135 960);
WIRE 16 -1 (-2275 1475)(-1450 1475);
FORCEPROP 2 LAST SIG_NAME UART_CPU0_UART0_TX
J 0
(-2150 1485);
DISPLAY 0.489362 (-2150 1485);
WIRE 16 -1 (-7475 5525)(-6450 5525);
FORCEPROP 2 LAST SIG_NAME SVID_PVDDCR_CPU0_P0_SVC_R
J 0
(-7275 5535);
DISPLAY 0.489362 (-7275 5535);
CIRCLE (-2425 475)(-2210 475);
PAINT YELLOW (-2425 475);
DOT 1 (-150 2175);
DOT 1 (-150 2225);
DOT 1 (-6675 1475);
DOT 1 (-6550 2225);
DOT 1 (-7675 1475);
DOT 1 (-9050 3100);
DOT 1 (-9050 3050);
DOT 1 (-9050 3000);
DOT 1 (-9050 2950);
DOT 1 (-9050 2900);
DOT 1 (-7025 1475);
DOT 1 (-7675 1050);
DOT 1 (-9050 3150);
DOT 1 (-8675 4525);
DOT 1 (-5900 1775);
DOT 1 (-6700 2325);
DOT 1 (-6475 2175);
DOT 1 (-6350 2075);
DOT 1 (-6275 2025);
DOT 1 (-6200 1975);
DOT 1 (-6125 1925);
DOT 1 (-5975 1825);
DOT 1 (-8000 1100);
DOT 1 (-8000 1475);
DOT 1 (-7350 1475);
DOT 1 (-7025 950);
DOT 1 (-6675 900);
DOT 1 (-6375 850);
DOT 1 (-225 5600);
DOT 1 (-225 5550);
DOT 1 (-225 5500);
DOT 1 (-225 5450);
DOT 1 (-225 5350);
DOT 1 (-225 5400);
DOT 1 (-225 5300);
DOT 1 (-225 5250);
DOT 1 (-225 5200);
DOT 1 (-225 5150);
DOT 1 (-6625 2275);
DOT 1 (-7350 1000);
DOT 1 (-150 2275);
DOT 1 (-150 2900);
DOT 1 (-150 2850);
DOT 1 (-150 2800);
DOT 1 (-5650 1125);
FORCENOTE
XTRIG_L[7:4] OF THE BP ARE CONNECTED TO
(-2425 400) 0;
DISPLAY LEFT (-2425 400);
DISPLAY 1.021277 (-2425 400);
FORCENOTE
XTRIG_L[7:4] OF THE ASP RESPECTIVELY)
(-2425 350) 0;
DISPLAY LEFT (-2425 350);
DISPLAY 1.021277 (-2425 350);
FORCENOTE
LOW: VDDBT_RTC_G POWERED FROM 1.8 OR 1.5V SOURCE
(-5425 666) 0;
DISPLAY LEFT (-5425 666);
DISPLAY 1.021277 (-5425 666);
FORCENOTE
CAD NOTE: IF DEPOP R1533, PLEASE POP R536
(-2000 3625) 0;
DISPLAY LEFT (-2000 3625);
DISPLAY 1.021277 (-2000 3625);
FORCENOTE
HIGH: VDDBT_RTC_G POWERED FROM 3.0V SOURCE
(-5425 600) 0;
DISPLAY LEFT (-5425 600);
DISPLAY 1.021277 (-5425 600);
QUIT
